FILE_TYPE = MACRO_DRAWING;
SET COLOR_WIRE YELLOW;
SET COLOR_PROP ORANGE;
SET COLOR_DOT WHITE;
SET COLOR_ARC YELLOW;
SET COLOR_BODY GREEN;
SET COLOR_NOTE PURPLE;
SET PROP_DISPLAY VALUE;
SET PAGE_NUMBER P87;
FORCEADD OFFPAGE..2
R 2
(-3025 250);
FORCEPROP 2 LAST $XR0 87 
J 0
(-3249 250);
DISPLAY 0.638298 (-3249 250);
PAINT MONO (-3249 250);
FORCEPROP 2 LAST CDS_LIB standard
J 0
(-3025 250);
PAINT MONO (-3025 250);
DISPLAY INVISIBLE (-3025 250);
FORCEPROP 1 LAST OFFPAGE TRUE
J 2
(-3350 125);
DISPLAY 0.872340 (-3350 125);
DISPLAY INVISIBLE (-3350 125);
FORCEPROP 1 LAST COMMENT_BODY TRUE
J 2
(-2980 155);
DISPLAY 0.872340 (-2980 155);
PAINT GREEN (-2980 155);
DISPLAY INVISIBLE (-2980 155);
FORCEPROP 2 LAST PATH I1
J 0
(-2975 325);
DISPLAY 1.021277 (-2975 325);
DISPLAY INVISIBLE (-2975 325);
FORCEADD OFFPAGE..3
R 2
(-3025 2825);
FORCEPROP 2 LAST $XR1 86 
J 0
(-3364 2825);
DISPLAY 0.638298 (-3364 2825);
PAINT MONO (-3364 2825);
FORCEPROP 2 LAST $XR0 22 
J 0
(-3274 2825);
DISPLAY 0.638298 (-3274 2825);
PAINT MONO (-3274 2825);
FORCEPROP 2 LAST CDS_LIB standard
J 0
(-3025 2825);
PAINT MONO (-3025 2825);
DISPLAY INVISIBLE (-3025 2825);
FORCEPROP 1 LAST OFFPAGE TRUE
J 2
(-3350 2700);
DISPLAY 0.872340 (-3350 2700);
DISPLAY INVISIBLE (-3350 2700);
FORCEPROP 1 LAST COMMENT_BODY TRUE
J 2
(-2975 2725);
DISPLAY 0.872340 (-2975 2725);
PAINT GREEN (-2975 2725);
DISPLAY INVISIBLE (-2975 2725);
FORCEPROP 2 LAST PATH I10
J 0
(-2975 2900);
DISPLAY 1.021277 (-2975 2900);
DISPLAY INVISIBLE (-2975 2900);
FORCEADD TAP..1
(-450 3700);
FORCEPROP 3 LASTPIN (-500 3700) SIG_NAME M_C_CPU0_SA_DQ<21>
J 0
(-490 3710);
DISPLAY 0.659574 (-490 3710);
PAINT MONO (-490 3710);
DISPLAY INVISIBLE (-490 3710);
FORCEPROP 1 LASTPIN (-500 3700) BN 21
J 0
(-512 3708);
DISPLAY 0.680851 (-512 3708);
PAINT GREEN (-512 3708);
FORCEPROP 2 LAST CDS_LIB standard
J 0
(-450 3700);
PAINT MONO (-450 3700);
DISPLAY INVISIBLE (-450 3700);
FORCEPROP 1 LAST BODY_TYPE PLUMBING
J 0
(-450 3750);
DISPLAY 0.872340 (-450 3750);
PAINT GREEN (-450 3750);
DISPLAY INVISIBLE (-450 3750);
FORCEPROP 1 LAST HDL_TAP TRUE
J 0
(-125 3575);
DISPLAY 0.872340 (-125 3575);
DISPLAY INVISIBLE (-125 3575);
FORCEPROP 1 LAST PATH I100
J 0
(-452 3700);
DISPLAY 0.872340 (-452 3700);
PAINT GREEN (-452 3700);
DISPLAY INVISIBLE (-452 3700);
FORCEADD TAP..1
(-450 3750);
FORCEPROP 3 LASTPIN (-500 3750) SIG_NAME M_C_CPU0_SA_DQ<22>
J 0
(-490 3760);
DISPLAY 0.659574 (-490 3760);
PAINT MONO (-490 3760);
DISPLAY INVISIBLE (-490 3760);
FORCEPROP 1 LASTPIN (-500 3750) BN 22
J 0
(-512 3758);
DISPLAY 0.680851 (-512 3758);
PAINT GREEN (-512 3758);
FORCEPROP 2 LAST CDS_LIB standard
J 0
(-450 3750);
DISPLAY INVISIBLE (-450 3750);
FORCEPROP 1 LAST BODY_TYPE PLUMBING
J 0
(-450 3800);
DISPLAY 0.872340 (-450 3800);
PAINT GREEN (-450 3800);
DISPLAY INVISIBLE (-450 3800);
FORCEPROP 1 LAST HDL_TAP TRUE
J 0
(-125 3625);
DISPLAY 0.872340 (-125 3625);
DISPLAY INVISIBLE (-125 3625);
FORCEPROP 1 LAST PATH I101
J 0
(-452 3750);
DISPLAY 0.872340 (-452 3750);
PAINT GREEN (-452 3750);
DISPLAY INVISIBLE (-452 3750);
FORCEADD TAP..1
(-450 3850);
FORCEPROP 3 LASTPIN (-500 3850) SIG_NAME M_C_CPU0_SA_DQ<24>
J 0
(-490 3860);
DISPLAY 0.659574 (-490 3860);
PAINT MONO (-490 3860);
DISPLAY INVISIBLE (-490 3860);
FORCEPROP 1 LASTPIN (-500 3850) BN 24
J 0
(-512 3858);
DISPLAY 0.680851 (-512 3858);
PAINT GREEN (-512 3858);
FORCEPROP 2 LAST CDS_LIB standard
J 0
(-450 3850);
DISPLAY INVISIBLE (-450 3850);
FORCEPROP 1 LAST BODY_TYPE PLUMBING
J 0
(-450 3900);
DISPLAY 0.872340 (-450 3900);
PAINT GREEN (-450 3900);
DISPLAY INVISIBLE (-450 3900);
FORCEPROP 1 LAST HDL_TAP TRUE
J 0
(-125 3725);
DISPLAY 0.872340 (-125 3725);
DISPLAY INVISIBLE (-125 3725);
FORCEPROP 1 LAST PATH I102
J 0
(-452 3850);
DISPLAY 0.872340 (-452 3850);
PAINT GREEN (-452 3850);
DISPLAY INVISIBLE (-452 3850);
FORCEADD TAP..1
(-450 3800);
FORCEPROP 3 LASTPIN (-500 3800) SIG_NAME M_C_CPU0_SA_DQ<23>
J 0
(-490 3810);
DISPLAY 0.659574 (-490 3810);
PAINT MONO (-490 3810);
DISPLAY INVISIBLE (-490 3810);
FORCEPROP 1 LASTPIN (-500 3800) BN 23
J 0
(-512 3808);
DISPLAY 0.680851 (-512 3808);
PAINT GREEN (-512 3808);
FORCEPROP 2 LAST CDS_LIB standard
J 0
(-450 3800);
DISPLAY INVISIBLE (-450 3800);
FORCEPROP 1 LAST BODY_TYPE PLUMBING
J 0
(-450 3850);
DISPLAY 0.872340 (-450 3850);
PAINT GREEN (-450 3850);
DISPLAY INVISIBLE (-450 3850);
FORCEPROP 1 LAST HDL_TAP TRUE
J 0
(-125 3675);
DISPLAY 0.872340 (-125 3675);
DISPLAY INVISIBLE (-125 3675);
FORCEPROP 1 LAST PATH I103
J 0
(-452 3800);
DISPLAY 0.872340 (-452 3800);
PAINT GREEN (-452 3800);
DISPLAY INVISIBLE (-452 3800);
FORCEADD OFFPAGE..1
(-3025 4225);
FORCEPROP 2 LAST $XR1 86 
J 0
(-3336 4225);
DISPLAY 0.638298 (-3336 4225);
PAINT MONO (-3336 4225);
FORCEPROP 2 LAST $XR0 22 
J 0
(-3246 4225);
DISPLAY 0.638298 (-3246 4225);
PAINT MONO (-3246 4225);
FORCEPROP 2 LAST CDS_LIB standard
J 0
(-3025 4225);
PAINT MONO (-3025 4225);
DISPLAY INVISIBLE (-3025 4225);
FORCEPROP 1 LAST OFFPAGE TRUE
J 0
(-2700 4100);
DISPLAY 0.872340 (-2700 4100);
DISPLAY INVISIBLE (-2700 4100);
FORCEPROP 1 LAST COMMENT_BODY TRUE
J 0
(-2900 4125);
DISPLAY 0.872340 (-2900 4125);
PAINT GREEN (-2900 4125);
DISPLAY INVISIBLE (-2900 4125);
FORCEPROP 2 LAST PATH I104
J 0
(-2975 4300);
DISPLAY 1.021277 (-2975 4300);
DISPLAY INVISIBLE (-2975 4300);
FORCEADD TAP..1
R 2
(-2100 3950);
FORCEPROP 3 LASTPIN (-2050 3950) SIG_NAME M_C_CPU0_SA_CA<1>
J 0
(-2040 3960);
DISPLAY 0.659574 (-2040 3960);
PAINT MONO (-2040 3960);
DISPLAY INVISIBLE (-2040 3960);
FORCEPROP 1 LASTPIN (-2050 3950) BN 1
J 2
(-2038 3958);
DISPLAY 0.680851 (-2038 3958);
PAINT GREEN (-2038 3958);
FORCEPROP 2 LAST CDS_LIB standard
J 0
(-2100 3950);
DISPLAY INVISIBLE (-2100 3950);
FORCEPROP 1 LAST BODY_TYPE PLUMBING
J 2
(-2100 4000);
DISPLAY 0.872340 (-2100 4000);
PAINT GREEN (-2100 4000);
DISPLAY INVISIBLE (-2100 4000);
FORCEPROP 1 LAST HDL_TAP TRUE
J 2
(-2425 3825);
DISPLAY 0.872340 (-2425 3825);
DISPLAY INVISIBLE (-2425 3825);
FORCEPROP 1 LAST PATH I105
J 2
(-2098 3950);
DISPLAY 0.872340 (-2098 3950);
PAINT GREEN (-2098 3950);
DISPLAY INVISIBLE (-2098 3950);
FORCEADD TAP..1
R 2
(-2100 3900);
FORCEPROP 3 LASTPIN (-2050 3900) SIG_NAME M_C_CPU0_SA_CA<0>
J 0
(-2040 3910);
DISPLAY 0.659574 (-2040 3910);
PAINT MONO (-2040 3910);
DISPLAY INVISIBLE (-2040 3910);
FORCEPROP 1 LASTPIN (-2050 3900) BN 0
J 2
(-2038 3908);
DISPLAY 0.680851 (-2038 3908);
PAINT GREEN (-2038 3908);
FORCEPROP 2 LAST CDS_LIB standard
J 0
(-2100 3900);
DISPLAY INVISIBLE (-2100 3900);
FORCEPROP 1 LAST BODY_TYPE PLUMBING
J 2
(-2100 3950);
DISPLAY 0.872340 (-2100 3950);
PAINT GREEN (-2100 3950);
DISPLAY INVISIBLE (-2100 3950);
FORCEPROP 1 LAST HDL_TAP TRUE
J 2
(-2425 3775);
DISPLAY 0.872340 (-2425 3775);
DISPLAY INVISIBLE (-2425 3775);
FORCEPROP 1 LAST PATH I106
J 2
(-2098 3900);
DISPLAY 0.872340 (-2098 3900);
PAINT GREEN (-2098 3900);
DISPLAY INVISIBLE (-2098 3900);
FORCEADD TAP..1
R 2
(-2100 4100);
FORCEPROP 3 LASTPIN (-2050 4100) SIG_NAME M_C_CPU0_SA_CA<4>
J 0
(-2040 4110);
DISPLAY 0.659574 (-2040 4110);
PAINT MONO (-2040 4110);
DISPLAY INVISIBLE (-2040 4110);
FORCEPROP 1 LASTPIN (-2050 4100) BN 4
J 2
(-2038 4108);
DISPLAY 0.680851 (-2038 4108);
PAINT GREEN (-2038 4108);
FORCEPROP 2 LAST CDS_LIB standard
J 0
(-2100 4100);
DISPLAY INVISIBLE (-2100 4100);
FORCEPROP 1 LAST BODY_TYPE PLUMBING
J 2
(-2100 4150);
DISPLAY 0.872340 (-2100 4150);
PAINT GREEN (-2100 4150);
DISPLAY INVISIBLE (-2100 4150);
FORCEPROP 1 LAST HDL_TAP TRUE
J 2
(-2425 3975);
DISPLAY 0.872340 (-2425 3975);
DISPLAY INVISIBLE (-2425 3975);
FORCEPROP 1 LAST PATH I107
J 2
(-2098 4100);
DISPLAY 0.872340 (-2098 4100);
PAINT GREEN (-2098 4100);
DISPLAY INVISIBLE (-2098 4100);
FORCEADD TAP..1
R 2
(-2100 4050);
FORCEPROP 3 LASTPIN (-2050 4050) SIG_NAME M_C_CPU0_SA_CA<3>
J 0
(-2040 4060);
DISPLAY 0.659574 (-2040 4060);
PAINT MONO (-2040 4060);
DISPLAY INVISIBLE (-2040 4060);
FORCEPROP 1 LASTPIN (-2050 4050) BN 3
J 2
(-2038 4058);
DISPLAY 0.680851 (-2038 4058);
PAINT GREEN (-2038 4058);
FORCEPROP 2 LAST CDS_LIB standard
J 0
(-2100 4050);
DISPLAY INVISIBLE (-2100 4050);
FORCEPROP 1 LAST BODY_TYPE PLUMBING
J 2
(-2100 4100);
DISPLAY 0.872340 (-2100 4100);
PAINT GREEN (-2100 4100);
DISPLAY INVISIBLE (-2100 4100);
FORCEPROP 1 LAST HDL_TAP TRUE
J 2
(-2425 3925);
DISPLAY 0.872340 (-2425 3925);
DISPLAY INVISIBLE (-2425 3925);
FORCEPROP 1 LAST PATH I108
J 2
(-2098 4050);
DISPLAY 0.872340 (-2098 4050);
PAINT GREEN (-2098 4050);
DISPLAY INVISIBLE (-2098 4050);
FORCEADD TAP..1
R 2
(-2100 4000);
FORCEPROP 3 LASTPIN (-2050 4000) SIG_NAME M_C_CPU0_SA_CA<2>
J 0
(-2040 4010);
DISPLAY 0.659574 (-2040 4010);
PAINT MONO (-2040 4010);
DISPLAY INVISIBLE (-2040 4010);
FORCEPROP 1 LASTPIN (-2050 4000) BN 2
J 2
(-2038 4008);
DISPLAY 0.680851 (-2038 4008);
PAINT GREEN (-2038 4008);
FORCEPROP 2 LAST CDS_LIB standard
J 0
(-2100 4000);
DISPLAY INVISIBLE (-2100 4000);
FORCEPROP 1 LAST BODY_TYPE PLUMBING
J 2
(-2100 4050);
DISPLAY 0.872340 (-2100 4050);
PAINT GREEN (-2100 4050);
DISPLAY INVISIBLE (-2100 4050);
FORCEPROP 1 LAST HDL_TAP TRUE
J 2
(-2425 3875);
DISPLAY 0.872340 (-2425 3875);
DISPLAY INVISIBLE (-2425 3875);
FORCEPROP 1 LAST PATH I109
J 2
(-2098 4000);
DISPLAY 0.872340 (-2098 4000);
PAINT GREEN (-2098 4000);
DISPLAY INVISIBLE (-2098 4000);
FORCEADD OFFPAGE..1
(-3025 2900);
FORCEPROP 2 LAST $XR0 22 
J 0
(-3246 2900);
DISPLAY 0.638298 (-3246 2900);
PAINT MONO (-3246 2900);
FORCEPROP 2 LAST CDS_LIB standard
J 0
(-3025 2900);
PAINT MONO (-3025 2900);
DISPLAY INVISIBLE (-3025 2900);
FORCEPROP 1 LAST OFFPAGE TRUE
J 0
(-2700 2775);
DISPLAY 0.872340 (-2700 2775);
DISPLAY INVISIBLE (-2700 2775);
FORCEPROP 1 LAST COMMENT_BODY TRUE
J 0
(-2900 2800);
DISPLAY 0.872340 (-2900 2800);
PAINT GREEN (-2900 2800);
DISPLAY INVISIBLE (-2900 2800);
FORCEPROP 2 LAST PATH I11
J 0
(-2975 2975);
DISPLAY 1.021277 (-2975 2975);
DISPLAY INVISIBLE (-2975 2975);
FORCEADD TAP..1
R 2
(-2100 4150);
FORCEPROP 3 LASTPIN (-2050 4150) SIG_NAME M_C_CPU0_SA_CA<5>
J 0
(-2040 4160);
DISPLAY 0.659574 (-2040 4160);
PAINT MONO (-2040 4160);
DISPLAY INVISIBLE (-2040 4160);
FORCEPROP 1 LASTPIN (-2050 4150) BN 5
J 2
(-2038 4158);
DISPLAY 0.680851 (-2038 4158);
PAINT GREEN (-2038 4158);
FORCEPROP 2 LAST CDS_LIB standard
J 0
(-2100 4150);
DISPLAY INVISIBLE (-2100 4150);
FORCEPROP 1 LAST BODY_TYPE PLUMBING
J 2
(-2100 4200);
DISPLAY 0.872340 (-2100 4200);
PAINT GREEN (-2100 4200);
DISPLAY INVISIBLE (-2100 4200);
FORCEPROP 1 LAST HDL_TAP TRUE
J 2
(-2425 4025);
DISPLAY 0.872340 (-2425 4025);
DISPLAY INVISIBLE (-2425 4025);
FORCEPROP 1 LAST PATH I110
J 2
(-2098 4150);
DISPLAY 0.872340 (-2098 4150);
PAINT GREEN (-2098 4150);
DISPLAY INVISIBLE (-2098 4150);
FORCEADD TAP..1
R 2
(-2100 4200);
FORCEPROP 3 LASTPIN (-2050 4200) SIG_NAME M_C_CPU0_SA_CA<6>
J 0
(-2040 4210);
DISPLAY 0.659574 (-2040 4210);
PAINT MONO (-2040 4210);
DISPLAY INVISIBLE (-2040 4210);
FORCEPROP 1 LASTPIN (-2050 4200) BN 6
J 2
(-2038 4208);
DISPLAY 0.680851 (-2038 4208);
PAINT GREEN (-2038 4208);
FORCEPROP 2 LAST CDS_LIB standard
J 0
(-2100 4200);
DISPLAY INVISIBLE (-2100 4200);
FORCEPROP 1 LAST BODY_TYPE PLUMBING
J 2
(-2100 4250);
DISPLAY 0.872340 (-2100 4250);
PAINT GREEN (-2100 4250);
DISPLAY INVISIBLE (-2100 4250);
FORCEPROP 1 LAST HDL_TAP TRUE
J 2
(-2425 4075);
DISPLAY 0.872340 (-2425 4075);
DISPLAY INVISIBLE (-2425 4075);
FORCEPROP 1 LAST PATH I111
J 2
(-2098 4200);
DISPLAY 0.872340 (-2098 4200);
PAINT GREEN (-2098 4200);
DISPLAY INVISIBLE (-2098 4200);
FORCEADD TAP..1
(-450 3950);
FORCEPROP 3 LASTPIN (-500 3950) SIG_NAME M_C_CPU0_SA_DQ<26>
J 0
(-490 3960);
DISPLAY 0.659574 (-490 3960);
PAINT MONO (-490 3960);
DISPLAY INVISIBLE (-490 3960);
FORCEPROP 1 LASTPIN (-500 3950) BN 26
J 0
(-512 3958);
DISPLAY 0.680851 (-512 3958);
PAINT GREEN (-512 3958);
FORCEPROP 2 LAST CDS_LIB standard
J 0
(-450 3950);
DISPLAY INVISIBLE (-450 3950);
FORCEPROP 1 LAST BODY_TYPE PLUMBING
J 0
(-450 4000);
DISPLAY 0.872340 (-450 4000);
PAINT GREEN (-450 4000);
DISPLAY INVISIBLE (-450 4000);
FORCEPROP 1 LAST HDL_TAP TRUE
J 0
(-125 3825);
DISPLAY 0.872340 (-125 3825);
DISPLAY INVISIBLE (-125 3825);
FORCEPROP 1 LAST PATH I112
J 0
(-452 3950);
DISPLAY 0.872340 (-452 3950);
PAINT GREEN (-452 3950);
DISPLAY INVISIBLE (-452 3950);
FORCEADD TAP..1
(-450 3900);
FORCEPROP 3 LASTPIN (-500 3900) SIG_NAME M_C_CPU0_SA_DQ<25>
J 0
(-490 3910);
DISPLAY 0.659574 (-490 3910);
PAINT MONO (-490 3910);
DISPLAY INVISIBLE (-490 3910);
FORCEPROP 1 LASTPIN (-500 3900) BN 25
J 0
(-512 3908);
DISPLAY 0.680851 (-512 3908);
PAINT GREEN (-512 3908);
FORCEPROP 2 LAST CDS_LIB standard
J 0
(-450 3900);
DISPLAY INVISIBLE (-450 3900);
FORCEPROP 1 LAST BODY_TYPE PLUMBING
J 0
(-450 3950);
DISPLAY 0.872340 (-450 3950);
PAINT GREEN (-450 3950);
DISPLAY INVISIBLE (-450 3950);
FORCEPROP 1 LAST HDL_TAP TRUE
J 0
(-125 3775);
DISPLAY 0.872340 (-125 3775);
DISPLAY INVISIBLE (-125 3775);
FORCEPROP 1 LAST PATH I113
J 0
(-452 3900);
DISPLAY 0.872340 (-452 3900);
PAINT GREEN (-452 3900);
DISPLAY INVISIBLE (-452 3900);
FORCEADD TAP..1
(-450 4000);
FORCEPROP 3 LASTPIN (-500 4000) SIG_NAME M_C_CPU0_SA_DQ<27>
J 0
(-490 4010);
DISPLAY 0.659574 (-490 4010);
PAINT MONO (-490 4010);
DISPLAY INVISIBLE (-490 4010);
FORCEPROP 1 LASTPIN (-500 4000) BN 27
J 0
(-512 4008);
DISPLAY 0.680851 (-512 4008);
PAINT GREEN (-512 4008);
FORCEPROP 2 LAST CDS_LIB standard
J 0
(-450 4000);
DISPLAY INVISIBLE (-450 4000);
FORCEPROP 1 LAST BODY_TYPE PLUMBING
J 0
(-450 4050);
DISPLAY 0.872340 (-450 4050);
PAINT GREEN (-450 4050);
DISPLAY INVISIBLE (-450 4050);
FORCEPROP 1 LAST HDL_TAP TRUE
J 0
(-125 3875);
DISPLAY 0.872340 (-125 3875);
DISPLAY INVISIBLE (-125 3875);
FORCEPROP 1 LAST PATH I114
J 0
(-452 4000);
DISPLAY 0.872340 (-452 4000);
PAINT GREEN (-452 4000);
DISPLAY INVISIBLE (-452 4000);
FORCEADD TAP..1
(-450 4050);
FORCEPROP 3 LASTPIN (-500 4050) SIG_NAME M_C_CPU0_SA_DQ<28>
J 0
(-490 4060);
DISPLAY 0.659574 (-490 4060);
PAINT MONO (-490 4060);
DISPLAY INVISIBLE (-490 4060);
FORCEPROP 1 LASTPIN (-500 4050) BN 28
J 0
(-512 4058);
DISPLAY 0.680851 (-512 4058);
PAINT GREEN (-512 4058);
FORCEPROP 2 LAST CDS_LIB standard
J 0
(-450 4050);
DISPLAY INVISIBLE (-450 4050);
FORCEPROP 1 LAST BODY_TYPE PLUMBING
J 0
(-450 4100);
DISPLAY 0.872340 (-450 4100);
PAINT GREEN (-450 4100);
DISPLAY INVISIBLE (-450 4100);
FORCEPROP 1 LAST HDL_TAP TRUE
J 0
(-125 3925);
DISPLAY 0.872340 (-125 3925);
DISPLAY INVISIBLE (-125 3925);
FORCEPROP 1 LAST PATH I115
J 0
(-452 4050);
DISPLAY 0.872340 (-452 4050);
PAINT GREEN (-452 4050);
DISPLAY INVISIBLE (-452 4050);
FORCEADD TAP..1
(-450 4100);
FORCEPROP 3 LASTPIN (-500 4100) SIG_NAME M_C_CPU0_SA_DQ<29>
J 0
(-490 4110);
DISPLAY 0.659574 (-490 4110);
PAINT MONO (-490 4110);
DISPLAY INVISIBLE (-490 4110);
FORCEPROP 1 LASTPIN (-500 4100) BN 29
J 0
(-512 4108);
DISPLAY 0.680851 (-512 4108);
PAINT GREEN (-512 4108);
FORCEPROP 2 LAST CDS_LIB standard
J 0
(-450 4100);
DISPLAY INVISIBLE (-450 4100);
FORCEPROP 1 LAST BODY_TYPE PLUMBING
J 0
(-450 4150);
DISPLAY 0.872340 (-450 4150);
PAINT GREEN (-450 4150);
DISPLAY INVISIBLE (-450 4150);
FORCEPROP 1 LAST HDL_TAP TRUE
J 0
(-125 3975);
DISPLAY 0.872340 (-125 3975);
DISPLAY INVISIBLE (-125 3975);
FORCEPROP 1 LAST PATH I116
J 0
(-452 4100);
DISPLAY 0.872340 (-452 4100);
PAINT GREEN (-452 4100);
DISPLAY INVISIBLE (-452 4100);
FORCEADD TAP..1
(-450 4150);
FORCEPROP 3 LASTPIN (-500 4150) SIG_NAME M_C_CPU0_SA_DQ<30>
J 0
(-490 4160);
DISPLAY 0.659574 (-490 4160);
PAINT MONO (-490 4160);
DISPLAY INVISIBLE (-490 4160);
FORCEPROP 1 LASTPIN (-500 4150) BN 30
J 0
(-512 4158);
DISPLAY 0.680851 (-512 4158);
PAINT GREEN (-512 4158);
FORCEPROP 2 LAST CDS_LIB standard
J 0
(-450 4150);
DISPLAY INVISIBLE (-450 4150);
FORCEPROP 1 LAST BODY_TYPE PLUMBING
J 0
(-450 4200);
DISPLAY 0.872340 (-450 4200);
PAINT GREEN (-450 4200);
DISPLAY INVISIBLE (-450 4200);
FORCEPROP 1 LAST HDL_TAP TRUE
J 0
(-125 4025);
DISPLAY 0.872340 (-125 4025);
DISPLAY INVISIBLE (-125 4025);
FORCEPROP 1 LAST PATH I117
J 0
(-452 4150);
DISPLAY 0.872340 (-452 4150);
PAINT GREEN (-452 4150);
DISPLAY INVISIBLE (-452 4150);
FORCEADD TAP..1
(-450 4200);
FORCEPROP 3 LASTPIN (-500 4200) SIG_NAME M_C_CPU0_SA_DQ<31>
J 0
(-490 4210);
DISPLAY 0.659574 (-490 4210);
PAINT MONO (-490 4210);
DISPLAY INVISIBLE (-490 4210);
FORCEPROP 1 LASTPIN (-500 4200) BN 31
J 0
(-512 4208);
DISPLAY 0.680851 (-512 4208);
PAINT GREEN (-512 4208);
FORCEPROP 2 LAST CDS_LIB standard
J 0
(-450 4200);
DISPLAY INVISIBLE (-450 4200);
FORCEPROP 1 LAST BODY_TYPE PLUMBING
J 0
(-450 4250);
DISPLAY 0.872340 (-450 4250);
PAINT GREEN (-450 4250);
DISPLAY INVISIBLE (-450 4250);
FORCEPROP 1 LAST HDL_TAP TRUE
J 0
(-125 4075);
DISPLAY 0.872340 (-125 4075);
DISPLAY INVISIBLE (-125 4075);
FORCEPROP 1 LAST PATH I118
J 0
(-452 4200);
DISPLAY 0.872340 (-452 4200);
PAINT GREEN (-452 4200);
DISPLAY INVISIBLE (-452 4200);
FORCEADD UNIVERSAL_GND..1
(1275 -50);
FORCEPROP 3 LASTPIN (1275 0) SIG_NAME GND\g
J 0
(1285 10);
DISPLAY 0.659574 (1285 10);
PAINT MONO (1285 10);
DISPLAY INVISIBLE (1285 10);
FORCEPROP 2 LAST CDS_LIB logical_power
J 0
(1275 -50);
PAINT MONO (1275 -50);
DISPLAY INVISIBLE (1275 -50);
FORCEPROP 1 LAST HDL_POWER GND
J 1
(1300 -125);
DISPLAY 0.872340 (1300 -125);
PAINT GREEN (1300 -125);
DISPLAY INVISIBLE (1300 -125);
FORCEPROP 1 LAST PATH I119
J 0
(1350 -50);
DISPLAY 0.872340 (1350 -50);
PAINT AQUA (1350 -50);
DISPLAY INVISIBLE (1350 -50);
FORCEADD OFFPAGE..1
(-3025 2950);
FORCEPROP 2 LAST $XR0 22 
J 0
(-3246 2950);
DISPLAY 0.638298 (-3246 2950);
PAINT MONO (-3246 2950);
FORCEPROP 2 LAST CDS_LIB standard
J 0
(-3025 2950);
PAINT MONO (-3025 2950);
DISPLAY INVISIBLE (-3025 2950);
FORCEPROP 1 LAST OFFPAGE TRUE
J 0
(-2700 2825);
DISPLAY 0.872340 (-2700 2825);
DISPLAY INVISIBLE (-2700 2825);
FORCEPROP 1 LAST COMMENT_BODY TRUE
J 0
(-2900 2850);
DISPLAY 0.872340 (-2900 2850);
PAINT GREEN (-2900 2850);
DISPLAY INVISIBLE (-2900 2850);
FORCEPROP 2 LAST PATH I12
J 0
(-2975 3025);
DISPLAY 1.021277 (-2975 3025);
DISPLAY INVISIBLE (-2975 3025);
FORCEADD Q_CAP..1
(1275 325);
FORCEPROP 1 LAST PART_NUMBER CH5221MEB00
J 0
(1325 175);
DISPLAY 0.978723 (1325 175);
DISPLAY INVISIBLE (1325 175);
FORCEPROP 1 LAST VOLTAGE 6.3V
J 0
(1325 325);
DISPLAY 0.978723 (1325 325);
FORCEPROP 1 LAST MATERIAL X6S
J 0
(1325 225);
DISPLAY 0.978723 (1325 225);
FORCEPROP 1 LAST TOLERANCE 20%
J 0
(1325 275);
DISPLAY 0.978723 (1325 275);
FORCEPROP 1 LAST VALUE 2.2UF
J 0
(1325 375);
DISPLAY 0.978723 (1325 375);
FORCEPROP 1 LAST PACK_TYPE C0402
J 0
(1325 125);
DISPLAY 0.978723 (1325 125);
FORCEPROP 1 LAST $LOCATION C17
J 0
(1325 425);
DISPLAY 0.978723 (1325 425);
FORCEPROP 1 LASTPIN (1275 425) $PN 1
J 0
(1285 405);
DISPLAY 0.787234 (1285 405);
FORCEPROP 1 LASTPIN (1275 225) $PN 2
J 0
(1285 205);
DISPLAY 0.787234 (1285 205);
FORCEPROP 2 LAST CDS_LIB pure_quanta
J 0
(1275 325);
PAINT MONO (1275 325);
DISPLAY INVISIBLE (1275 325);
FORCEPROP 2 LAST CDS_LOCATION C17
J 0
(1325 525);
DISPLAY 1.021277 (1325 525);
DISPLAY INVISIBLE (1325 525);
FORCEPROP 2 LAST $SEC 1
J 0
(1325 525);
DISPLAY 0.680851 (1325 525);
PAINT MONO (1325 525);
DISPLAY INVISIBLE (1325 525);
FORCEPROP 2 LAST CDS_SEC 1
J 0
(1325 525);
DISPLAY 1.021277 (1325 525);
DISPLAY INVISIBLE (1325 525);
FORCEPROP 1 LAST PATH I120
J 0
(1325 475);
DISPLAY 0.978723 (1325 475);
PAINT WHITE (1325 475);
DISPLAY INVISIBLE (1325 475);
FORCEADD VCC_CORE..1
(1275 650);
FORCEPROP 3 LASTPIN (1275 600) SIG_NAME P3V3_AUX\g
J 0
(1285 610);
DISPLAY 0.659574 (1285 610);
PAINT MONO (1285 610);
DISPLAY INVISIBLE (1285 610);
FORCEPROP 1 LAST HDL_POWER P3V3_AUX
J 1
(1275 700);
DISPLAY 1.148936 (1275 700);
PAINT GREEN (1275 700);
FORCEPROP 2 LAST CDS_LIB logical_power
J 0
(1275 650);
PAINT MONO (1275 650);
DISPLAY INVISIBLE (1275 650);
FORCEPROP 1 LAST PATH I121
J 0
(1325 675);
DISPLAY 0.872340 (1325 675);
PAINT AQUA (1325 675);
DISPLAY INVISIBLE (1325 675);
FORCEADD OFFPAGE..3
(375 2575);
FORCEPROP 2 LAST $XR1 86 
J 0
(679 2575);
DISPLAY 0.638298 (679 2575);
PAINT MONO (679 2575);
FORCEPROP 2 LAST $XR0 22 
J 0
(589 2575);
DISPLAY 0.638298 (589 2575);
PAINT MONO (589 2575);
FORCEPROP 2 LAST CDS_LIB standard
J 2
(375 2575);
DISPLAY INVISIBLE (375 2575);
FORCEPROP 1 LAST OFFPAGE TRUE
J 0
(700 2450);
DISPLAY 0.872340 (700 2450);
DISPLAY INVISIBLE (700 2450);
FORCEPROP 1 LAST COMMENT_BODY TRUE
J 0
(325 2475);
DISPLAY 0.872340 (325 2475);
PAINT GREEN (325 2475);
DISPLAY INVISIBLE (325 2475);
FORCEPROP 2 LAST PATH I122
J 0
(575 2650);
DISPLAY 1.021277 (575 2650);
DISPLAY INVISIBLE (575 2650);
FORCEADD Q_CAP..1
(2275 325);
FORCEPROP 1 LAST PART_NUMBER CH6103KEA00
J 0
(2325 175);
DISPLAY 0.978723 (2325 175);
DISPLAY INVISIBLE (2325 175);
FORCEPROP 1 LAST PACK_TYPE C0805
J 0
(2325 125);
DISPLAY 0.978723 (2325 125);
FORCEPROP 1 LAST MATERIAL X6S
J 0
(2325 225);
DISPLAY 0.978723 (2325 225);
FORCEPROP 1 LAST VALUE 10UF
J 0
(2325 375);
DISPLAY 0.978723 (2325 375);
FORCEPROP 1 LAST VOLTAGE 16V
J 0
(2325 325);
DISPLAY 0.978723 (2325 325);
FORCEPROP 1 LAST TOLERANCE 10%
J 0
(2325 275);
DISPLAY 0.978723 (2325 275);
FORCEPROP 1 LAST $LOCATION C18
J 0
(2325 425);
DISPLAY 0.978723 (2325 425);
FORCEPROP 1 LASTPIN (2275 425) $PN 1
J 0
(2285 405);
DISPLAY 0.787234 (2285 405);
FORCEPROP 1 LASTPIN (2275 225) $PN 2
J 0
(2285 205);
DISPLAY 0.787234 (2285 205);
FORCEPROP 2 LAST CDS_LIB pure_quanta
J 0
(2275 325);
PAINT MONO (2275 325);
DISPLAY INVISIBLE (2275 325);
FORCEPROP 2 LAST CDS_LOCATION C18
J 0
(2325 525);
DISPLAY 1.021277 (2325 525);
DISPLAY INVISIBLE (2325 525);
FORCEPROP 2 LAST $SEC 1
J 0
(2325 525);
DISPLAY 0.680851 (2325 525);
PAINT MONO (2325 525);
DISPLAY INVISIBLE (2325 525);
FORCEPROP 2 LAST CDS_SEC 1
J 0
(2325 525);
DISPLAY 1.021277 (2325 525);
DISPLAY INVISIBLE (2325 525);
FORCEPROP 1 LAST PATH I124
J 0
(2325 475);
DISPLAY 0.978723 (2325 475);
PAINT WHITE (2325 475);
DISPLAY INVISIBLE (2325 475);
FORCEADD VCC_CORE..1
(2275 650);
FORCEPROP 3 LASTPIN (2275 600) SIG_NAME P12V_S3_AUX_CPU0_NVDIMM\g
J 0
(2285 610);
DISPLAY 0.659574 (2285 610);
PAINT MONO (2285 610);
DISPLAY INVISIBLE (2285 610);
FORCEPROP 1 LAST HDL_POWER P12V_S3_AUX_CPU0_NVDIMM
J 1
(2275 700);
DISPLAY 1.148936 (2275 700);
PAINT GREEN (2275 700);
FORCEPROP 2 LAST CDS_LIB logical_power
J 0
(2275 650);
PAINT MONO (2275 650);
DISPLAY INVISIBLE (2275 650);
FORCEPROP 1 LAST PATH I125
J 0
(2325 675);
DISPLAY 0.872340 (2325 675);
PAINT AQUA (2325 675);
DISPLAY INVISIBLE (2325 675);
FORCEADD UNIVERSAL_GND..1
(2900 -50);
FORCEPROP 3 LASTPIN (2900 0) SIG_NAME GND\g
J 0
(2910 10);
DISPLAY 0.659574 (2910 10);
PAINT MONO (2910 10);
DISPLAY INVISIBLE (2910 10);
FORCEPROP 2 LAST CDS_LIB logical_power
J 0
(2900 -50);
PAINT MONO (2900 -50);
DISPLAY INVISIBLE (2900 -50);
FORCEPROP 1 LAST HDL_POWER GND
J 1
(2925 -125);
DISPLAY 0.872340 (2925 -125);
PAINT GREEN (2925 -125);
DISPLAY INVISIBLE (2925 -125);
FORCEPROP 1 LAST PATH I126
J 0
(2975 -50);
DISPLAY 0.872340 (2975 -50);
PAINT AQUA (2975 -50);
DISPLAY INVISIBLE (2975 -50);
FORCEADD Q_CAP..1
(2900 325);
FORCEPROP 1 LAST PART_NUMBER CH6103KEA00
J 0
(2950 175);
DISPLAY 0.978723 (2950 175);
DISPLAY INVISIBLE (2950 175);
FORCEPROP 1 LAST TOLERANCE 10%
J 0
(2950 275);
DISPLAY 0.978723 (2950 275);
FORCEPROP 1 LAST VALUE 10UF
J 0
(2950 375);
DISPLAY 0.978723 (2950 375);
FORCEPROP 1 LAST PACK_TYPE C0805
J 0
(2950 125);
DISPLAY 0.978723 (2950 125);
FORCEPROP 1 LAST VOLTAGE 16V
J 0
(2950 325);
DISPLAY 0.978723 (2950 325);
FORCEPROP 1 LAST MATERIAL X6S
J 0
(2950 225);
DISPLAY 0.978723 (2950 225);
FORCEPROP 1 LAST $LOCATION C19
J 0
(2950 425);
DISPLAY 0.978723 (2950 425);
FORCEPROP 1 LASTPIN (2900 425) $PN 1
J 0
(2910 405);
DISPLAY 0.787234 (2910 405);
FORCEPROP 1 LASTPIN (2900 225) $PN 2
J 0
(2910 205);
DISPLAY 0.787234 (2910 205);
FORCEPROP 2 LAST CDS_LIB pure_quanta
J 0
(2900 325);
PAINT MONO (2900 325);
DISPLAY INVISIBLE (2900 325);
FORCEPROP 2 LAST CDS_LOCATION C19
J 0
(2950 525);
DISPLAY 1.021277 (2950 525);
DISPLAY INVISIBLE (2950 525);
FORCEPROP 2 LAST $SEC 1
J 0
(2950 525);
DISPLAY 0.680851 (2950 525);
PAINT MONO (2950 525);
DISPLAY INVISIBLE (2950 525);
FORCEPROP 2 LAST CDS_SEC 1
J 0
(2950 525);
DISPLAY 1.021277 (2950 525);
DISPLAY INVISIBLE (2950 525);
FORCEPROP 1 LAST PATH I127
J 0
(2950 475);
DISPLAY 0.978723 (2950 475);
PAINT WHITE (2950 475);
DISPLAY INVISIBLE (2950 475);
FORCEADD UNIVERSAL_GND..1
(3975 500);
FORCEPROP 3 LASTPIN (3975 550) SIG_NAME GND\g
J 0
(3985 560);
DISPLAY 0.659574 (3985 560);
PAINT MONO (3985 560);
DISPLAY INVISIBLE (3985 560);
FORCEPROP 2 LAST CDS_LIB logical_power
J 0
(3975 500);
PAINT MONO (3975 500);
DISPLAY INVISIBLE (3975 500);
FORCEPROP 1 LAST HDL_POWER GND
J 1
(4000 425);
DISPLAY 0.872340 (4000 425);
PAINT GREEN (4000 425);
DISPLAY INVISIBLE (4000 425);
FORCEPROP 1 LAST PATH I128
J 0
(4050 500);
DISPLAY 0.872340 (4050 500);
PAINT AQUA (4050 500);
DISPLAY INVISIBLE (4050 500);
FORCEADD TAP..1
(2300 2350);
FORCEPROP 3 LASTPIN (2250 2350) SIG_NAME M_C_CPU0_SB_DQS_DP<1>
J 0
(2260 2360);
DISPLAY 0.659574 (2260 2360);
PAINT MONO (2260 2360);
DISPLAY INVISIBLE (2260 2360);
FORCEPROP 1 LASTPIN (2250 2350) BN 1
J 0
(2238 2358);
DISPLAY 0.680851 (2238 2358);
PAINT GREEN (2238 2358);
FORCEPROP 2 LAST CDS_LIB standard
J 0
(2300 2350);
DISPLAY INVISIBLE (2300 2350);
FORCEPROP 1 LAST BODY_TYPE PLUMBING
J 0
(2300 2400);
DISPLAY 0.872340 (2300 2400);
PAINT GREEN (2300 2400);
DISPLAY INVISIBLE (2300 2400);
FORCEPROP 1 LAST HDL_TAP TRUE
J 0
(2625 2225);
DISPLAY 0.872340 (2625 2225);
DISPLAY INVISIBLE (2625 2225);
FORCEPROP 1 LAST PATH I129
J 0
(2298 2350);
DISPLAY 0.872340 (2298 2350);
PAINT GREEN (2298 2350);
DISPLAY INVISIBLE (2298 2350);
FORCEADD OFFPAGE..1
(-3025 3050);
FORCEPROP 2 LAST $XR0 22 
J 0
(-3246 3050);
DISPLAY 0.638298 (-3246 3050);
PAINT MONO (-3246 3050);
FORCEPROP 2 LAST CDS_LIB standard
J 0
(-3025 3050);
PAINT MONO (-3025 3050);
DISPLAY INVISIBLE (-3025 3050);
FORCEPROP 1 LAST OFFPAGE TRUE
J 0
(-2700 2925);
DISPLAY 0.872340 (-2700 2925);
DISPLAY INVISIBLE (-2700 2925);
FORCEPROP 1 LAST COMMENT_BODY TRUE
J 0
(-2900 2950);
DISPLAY 0.872340 (-2900 2950);
PAINT GREEN (-2900 2950);
DISPLAY INVISIBLE (-2900 2950);
FORCEPROP 2 LAST PATH I13
J 0
(-2975 3125);
DISPLAY 1.021277 (-2975 3125);
DISPLAY INVISIBLE (-2975 3125);
FORCEADD TAP..1
(2300 2250);
FORCEPROP 3 LASTPIN (2250 2250) SIG_NAME M_C_CPU0_SB_DQS_DP<0>
J 0
(2260 2260);
DISPLAY 0.659574 (2260 2260);
PAINT MONO (2260 2260);
DISPLAY INVISIBLE (2260 2260);
FORCEPROP 1 LASTPIN (2250 2250) BN 0
J 0
(2238 2258);
DISPLAY 0.680851 (2238 2258);
PAINT GREEN (2238 2258);
FORCEPROP 2 LAST CDS_LIB standard
J 0
(2300 2250);
PAINT MONO (2300 2250);
DISPLAY INVISIBLE (2300 2250);
FORCEPROP 1 LAST BODY_TYPE PLUMBING
J 0
(2300 2300);
DISPLAY 0.872340 (2300 2300);
PAINT GREEN (2300 2300);
DISPLAY INVISIBLE (2300 2300);
FORCEPROP 1 LAST HDL_TAP TRUE
J 0
(2625 2125);
DISPLAY 0.872340 (2625 2125);
DISPLAY INVISIBLE (2625 2125);
FORCEPROP 1 LAST PATH I130
J 0
(2298 2250);
DISPLAY 0.872340 (2298 2250);
PAINT GREEN (2298 2250);
DISPLAY INVISIBLE (2298 2250);
FORCEADD TAP..1
(2475 2200);
FORCEPROP 3 LASTPIN (2425 2200) SIG_NAME M_C_CPU0_SB_DQS_DN<0>
J 0
(2435 2210);
DISPLAY 0.659574 (2435 2210);
PAINT MONO (2435 2210);
DISPLAY INVISIBLE (2435 2210);
FORCEPROP 1 LASTPIN (2425 2200) BN 0
J 0
(2413 2208);
DISPLAY 0.680851 (2413 2208);
PAINT GREEN (2413 2208);
FORCEPROP 2 LAST CDS_LIB standard
J 0
(2475 2200);
PAINT MONO (2475 2200);
DISPLAY INVISIBLE (2475 2200);
FORCEPROP 1 LAST BODY_TYPE PLUMBING
J 0
(2475 2250);
DISPLAY 0.872340 (2475 2250);
PAINT GREEN (2475 2250);
DISPLAY INVISIBLE (2475 2250);
FORCEPROP 1 LAST HDL_TAP TRUE
J 0
(2800 2075);
DISPLAY 0.872340 (2800 2075);
DISPLAY INVISIBLE (2800 2075);
FORCEPROP 1 LAST PATH I131
J 0
(2473 2200);
DISPLAY 0.872340 (2473 2200);
PAINT GREEN (2473 2200);
DISPLAY INVISIBLE (2473 2200);
FORCEADD TAP..1
(2475 2300);
FORCEPROP 3 LASTPIN (2425 2300) SIG_NAME M_C_CPU0_SB_DQS_DN<1>
J 0
(2435 2310);
DISPLAY 0.659574 (2435 2310);
PAINT MONO (2435 2310);
DISPLAY INVISIBLE (2435 2310);
FORCEPROP 1 LASTPIN (2425 2300) BN 1
J 0
(2413 2308);
DISPLAY 0.680851 (2413 2308);
PAINT GREEN (2413 2308);
FORCEPROP 2 LAST CDS_LIB standard
J 0
(2475 2300);
DISPLAY INVISIBLE (2475 2300);
FORCEPROP 1 LAST BODY_TYPE PLUMBING
J 0
(2475 2350);
DISPLAY 0.872340 (2475 2350);
PAINT GREEN (2475 2350);
DISPLAY INVISIBLE (2475 2350);
FORCEPROP 1 LAST HDL_TAP TRUE
J 0
(2800 2175);
DISPLAY 0.872340 (2800 2175);
DISPLAY INVISIBLE (2800 2175);
FORCEPROP 1 LAST PATH I132
J 0
(2473 2300);
DISPLAY 0.872340 (2473 2300);
PAINT GREEN (2473 2300);
DISPLAY INVISIBLE (2473 2300);
FORCEADD TAP..1
(2300 2550);
FORCEPROP 3 LASTPIN (2250 2550) SIG_NAME M_C_CPU0_SB_DQS_DP<3>
J 0
(2260 2560);
DISPLAY 0.659574 (2260 2560);
PAINT MONO (2260 2560);
DISPLAY INVISIBLE (2260 2560);
FORCEPROP 1 LASTPIN (2250 2550) BN 3
J 0
(2238 2558);
DISPLAY 0.680851 (2238 2558);
PAINT GREEN (2238 2558);
FORCEPROP 2 LAST CDS_LIB standard
J 0
(2300 2550);
PAINT MONO (2300 2550);
DISPLAY INVISIBLE (2300 2550);
FORCEPROP 1 LAST BODY_TYPE PLUMBING
J 0
(2300 2600);
DISPLAY 0.872340 (2300 2600);
PAINT GREEN (2300 2600);
DISPLAY INVISIBLE (2300 2600);
FORCEPROP 1 LAST HDL_TAP TRUE
J 0
(2625 2425);
DISPLAY 0.872340 (2625 2425);
DISPLAY INVISIBLE (2625 2425);
FORCEPROP 1 LAST PATH I133
J 0
(2298 2550);
DISPLAY 0.872340 (2298 2550);
PAINT GREEN (2298 2550);
DISPLAY INVISIBLE (2298 2550);
FORCEADD TAP..1
(2300 2450);
FORCEPROP 3 LASTPIN (2250 2450) SIG_NAME M_C_CPU0_SB_DQS_DP<2>
J 0
(2260 2460);
DISPLAY 0.659574 (2260 2460);
PAINT MONO (2260 2460);
DISPLAY INVISIBLE (2260 2460);
FORCEPROP 1 LASTPIN (2250 2450) BN 2
J 0
(2238 2458);
DISPLAY 0.680851 (2238 2458);
PAINT GREEN (2238 2458);
FORCEPROP 2 LAST CDS_LIB standard
J 0
(2300 2450);
DISPLAY INVISIBLE (2300 2450);
FORCEPROP 1 LAST BODY_TYPE PLUMBING
J 0
(2300 2500);
DISPLAY 0.872340 (2300 2500);
PAINT GREEN (2300 2500);
DISPLAY INVISIBLE (2300 2500);
FORCEPROP 1 LAST HDL_TAP TRUE
J 0
(2625 2325);
DISPLAY 0.872340 (2625 2325);
DISPLAY INVISIBLE (2625 2325);
FORCEPROP 1 LAST PATH I134
J 0
(2298 2450);
DISPLAY 0.872340 (2298 2450);
PAINT GREEN (2298 2450);
DISPLAY INVISIBLE (2298 2450);
FORCEADD TAP..1
(2475 2400);
FORCEPROP 3 LASTPIN (2425 2400) SIG_NAME M_C_CPU0_SB_DQS_DN<2>
J 0
(2435 2410);
DISPLAY 0.659574 (2435 2410);
PAINT MONO (2435 2410);
DISPLAY INVISIBLE (2435 2410);
FORCEPROP 1 LASTPIN (2425 2400) BN 2
J 0
(2413 2408);
DISPLAY 0.680851 (2413 2408);
PAINT GREEN (2413 2408);
FORCEPROP 2 LAST CDS_LIB standard
J 0
(2475 2400);
DISPLAY INVISIBLE (2475 2400);
FORCEPROP 1 LAST BODY_TYPE PLUMBING
J 0
(2475 2450);
DISPLAY 0.872340 (2475 2450);
PAINT GREEN (2475 2450);
DISPLAY INVISIBLE (2475 2450);
FORCEPROP 1 LAST HDL_TAP TRUE
J 0
(2800 2275);
DISPLAY 0.872340 (2800 2275);
DISPLAY INVISIBLE (2800 2275);
FORCEPROP 1 LAST PATH I135
J 0
(2473 2400);
DISPLAY 0.872340 (2473 2400);
PAINT GREEN (2473 2400);
DISPLAY INVISIBLE (2473 2400);
FORCEADD TAP..1
(2475 2500);
FORCEPROP 3 LASTPIN (2425 2500) SIG_NAME M_C_CPU0_SB_DQS_DN<3>
J 0
(2435 2510);
DISPLAY 0.659574 (2435 2510);
PAINT MONO (2435 2510);
DISPLAY INVISIBLE (2435 2510);
FORCEPROP 1 LASTPIN (2425 2500) BN 3
J 0
(2413 2508);
DISPLAY 0.680851 (2413 2508);
PAINT GREEN (2413 2508);
FORCEPROP 2 LAST CDS_LIB standard
J 0
(2475 2500);
PAINT MONO (2475 2500);
DISPLAY INVISIBLE (2475 2500);
FORCEPROP 1 LAST BODY_TYPE PLUMBING
J 0
(2475 2550);
DISPLAY 0.872340 (2475 2550);
PAINT GREEN (2475 2550);
DISPLAY INVISIBLE (2475 2550);
FORCEPROP 1 LAST HDL_TAP TRUE
J 0
(2800 2375);
DISPLAY 0.872340 (2800 2375);
DISPLAY INVISIBLE (2800 2375);
FORCEPROP 1 LAST PATH I136
J 0
(2473 2500);
DISPLAY 0.872340 (2473 2500);
PAINT GREEN (2473 2500);
DISPLAY INVISIBLE (2473 2500);
FORCEADD TAP..1
(2475 2600);
FORCEPROP 3 LASTPIN (2425 2600) SIG_NAME M_C_CPU0_SB_DQS_DN<4>
J 0
(2435 2610);
DISPLAY 0.659574 (2435 2610);
PAINT MONO (2435 2610);
DISPLAY INVISIBLE (2435 2610);
FORCEPROP 1 LASTPIN (2425 2600) BN 4
J 0
(2413 2608);
DISPLAY 0.680851 (2413 2608);
PAINT GREEN (2413 2608);
FORCEPROP 2 LAST CDS_LIB standard
J 0
(2475 2600);
PAINT MONO (2475 2600);
DISPLAY INVISIBLE (2475 2600);
FORCEPROP 1 LAST BODY_TYPE PLUMBING
J 0
(2475 2650);
DISPLAY 0.872340 (2475 2650);
PAINT GREEN (2475 2650);
DISPLAY INVISIBLE (2475 2650);
FORCEPROP 1 LAST HDL_TAP TRUE
J 0
(2800 2475);
DISPLAY 0.872340 (2800 2475);
DISPLAY INVISIBLE (2800 2475);
FORCEPROP 1 LAST PATH I137
J 0
(2473 2600);
DISPLAY 0.872340 (2473 2600);
PAINT GREEN (2473 2600);
DISPLAY INVISIBLE (2473 2600);
FORCEADD TAP..1
(2300 2650);
FORCEPROP 3 LASTPIN (2250 2650) SIG_NAME M_C_CPU0_SB_DQS_DP<4>
J 0
(2260 2660);
DISPLAY 0.659574 (2260 2660);
PAINT MONO (2260 2660);
DISPLAY INVISIBLE (2260 2660);
FORCEPROP 1 LASTPIN (2250 2650) BN 4
J 0
(2238 2658);
DISPLAY 0.680851 (2238 2658);
PAINT GREEN (2238 2658);
FORCEPROP 2 LAST CDS_LIB standard
J 0
(2300 2650);
PAINT MONO (2300 2650);
DISPLAY INVISIBLE (2300 2650);
FORCEPROP 1 LAST BODY_TYPE PLUMBING
J 0
(2300 2700);
DISPLAY 0.872340 (2300 2700);
PAINT GREEN (2300 2700);
DISPLAY INVISIBLE (2300 2700);
FORCEPROP 1 LAST HDL_TAP TRUE
J 0
(2625 2525);
DISPLAY 0.872340 (2625 2525);
DISPLAY INVISIBLE (2625 2525);
FORCEPROP 1 LAST PATH I138
J 0
(2298 2650);
DISPLAY 0.872340 (2298 2650);
PAINT GREEN (2298 2650);
DISPLAY INVISIBLE (2298 2650);
FORCEADD TAP..1
(2300 2750);
FORCEPROP 3 LASTPIN (2250 2750) SIG_NAME M_C_CPU0_SB_DQS_DP<5>
J 0
(2260 2760);
DISPLAY 0.659574 (2260 2760);
PAINT MONO (2260 2760);
DISPLAY INVISIBLE (2260 2760);
FORCEPROP 1 LASTPIN (2250 2750) BN 5
J 0
(2238 2758);
DISPLAY 0.680851 (2238 2758);
PAINT GREEN (2238 2758);
FORCEPROP 2 LAST CDS_LIB standard
J 0
(2300 2750);
DISPLAY INVISIBLE (2300 2750);
FORCEPROP 1 LAST BODY_TYPE PLUMBING
J 0
(2300 2800);
DISPLAY 0.872340 (2300 2800);
PAINT GREEN (2300 2800);
DISPLAY INVISIBLE (2300 2800);
FORCEPROP 1 LAST HDL_TAP TRUE
J 0
(2625 2625);
DISPLAY 0.872340 (2625 2625);
DISPLAY INVISIBLE (2625 2625);
FORCEPROP 1 LAST PATH I139
J 0
(2298 2750);
DISPLAY 0.872340 (2298 2750);
PAINT GREEN (2298 2750);
DISPLAY INVISIBLE (2298 2750);
FORCEADD OFFPAGE..1
(-3025 3100);
FORCEPROP 2 LAST $XR0 22 
J 0
(-3246 3100);
DISPLAY 0.638298 (-3246 3100);
PAINT MONO (-3246 3100);
FORCEPROP 2 LAST CDS_LIB standard
J 0
(-3025 3100);
PAINT MONO (-3025 3100);
DISPLAY INVISIBLE (-3025 3100);
FORCEPROP 1 LAST OFFPAGE TRUE
J 0
(-2700 2975);
DISPLAY 0.872340 (-2700 2975);
DISPLAY INVISIBLE (-2700 2975);
FORCEPROP 1 LAST COMMENT_BODY TRUE
J 0
(-2900 3000);
DISPLAY 0.872340 (-2900 3000);
PAINT GREEN (-2900 3000);
DISPLAY INVISIBLE (-2900 3000);
FORCEPROP 2 LAST PATH I14
J 0
(-2975 3175);
DISPLAY 1.021277 (-2975 3175);
DISPLAY INVISIBLE (-2975 3175);
FORCEADD TAP..1
(2300 2850);
FORCEPROP 3 LASTPIN (2250 2850) SIG_NAME M_C_CPU0_SB_DQS_DP<6>
J 0
(2260 2860);
DISPLAY 0.659574 (2260 2860);
PAINT MONO (2260 2860);
DISPLAY INVISIBLE (2260 2860);
FORCEPROP 1 LASTPIN (2250 2850) BN 6
J 0
(2238 2858);
DISPLAY 0.680851 (2238 2858);
PAINT GREEN (2238 2858);
FORCEPROP 2 LAST CDS_LIB standard
J 0
(2300 2850);
DISPLAY INVISIBLE (2300 2850);
FORCEPROP 1 LAST BODY_TYPE PLUMBING
J 0
(2300 2900);
DISPLAY 0.872340 (2300 2900);
PAINT GREEN (2300 2900);
DISPLAY INVISIBLE (2300 2900);
FORCEPROP 1 LAST HDL_TAP TRUE
J 0
(2625 2725);
DISPLAY 0.872340 (2625 2725);
DISPLAY INVISIBLE (2625 2725);
FORCEPROP 1 LAST PATH I140
J 0
(2298 2850);
DISPLAY 0.872340 (2298 2850);
PAINT GREEN (2298 2850);
DISPLAY INVISIBLE (2298 2850);
FORCEADD TAP..1
(2475 2700);
FORCEPROP 3 LASTPIN (2425 2700) SIG_NAME M_C_CPU0_SB_DQS_DN<5>
J 0
(2435 2710);
DISPLAY 0.659574 (2435 2710);
PAINT MONO (2435 2710);
DISPLAY INVISIBLE (2435 2710);
FORCEPROP 1 LASTPIN (2425 2700) BN 5
J 0
(2413 2708);
DISPLAY 0.680851 (2413 2708);
PAINT GREEN (2413 2708);
FORCEPROP 2 LAST CDS_LIB standard
J 0
(2475 2700);
DISPLAY INVISIBLE (2475 2700);
FORCEPROP 1 LAST BODY_TYPE PLUMBING
J 0
(2475 2750);
DISPLAY 0.872340 (2475 2750);
PAINT GREEN (2475 2750);
DISPLAY INVISIBLE (2475 2750);
FORCEPROP 1 LAST HDL_TAP TRUE
J 0
(2800 2575);
DISPLAY 0.872340 (2800 2575);
DISPLAY INVISIBLE (2800 2575);
FORCEPROP 1 LAST PATH I141
J 0
(2473 2700);
DISPLAY 0.872340 (2473 2700);
PAINT GREEN (2473 2700);
DISPLAY INVISIBLE (2473 2700);
FORCEADD TAP..1
(2475 2800);
FORCEPROP 3 LASTPIN (2425 2800) SIG_NAME M_C_CPU0_SB_DQS_DN<6>
J 0
(2435 2810);
DISPLAY 0.659574 (2435 2810);
PAINT MONO (2435 2810);
DISPLAY INVISIBLE (2435 2810);
FORCEPROP 1 LASTPIN (2425 2800) BN 6
J 0
(2413 2808);
DISPLAY 0.680851 (2413 2808);
PAINT GREEN (2413 2808);
FORCEPROP 2 LAST CDS_LIB standard
J 0
(2475 2800);
DISPLAY INVISIBLE (2475 2800);
FORCEPROP 1 LAST BODY_TYPE PLUMBING
J 0
(2475 2850);
DISPLAY 0.872340 (2475 2850);
PAINT GREEN (2475 2850);
DISPLAY INVISIBLE (2475 2850);
FORCEPROP 1 LAST HDL_TAP TRUE
J 0
(2800 2675);
DISPLAY 0.872340 (2800 2675);
DISPLAY INVISIBLE (2800 2675);
FORCEPROP 1 LAST PATH I142
J 0
(2473 2800);
DISPLAY 0.872340 (2473 2800);
PAINT GREEN (2473 2800);
DISPLAY INVISIBLE (2473 2800);
FORCEADD TAP..1
(2300 3050);
FORCEPROP 3 LASTPIN (2250 3050) SIG_NAME M_C_CPU0_SB_DQS_DP<8>
J 0
(2260 3060);
DISPLAY 0.659574 (2260 3060);
PAINT MONO (2260 3060);
DISPLAY INVISIBLE (2260 3060);
FORCEPROP 1 LASTPIN (2250 3050) BN 8
J 0
(2238 3058);
DISPLAY 0.680851 (2238 3058);
PAINT GREEN (2238 3058);
FORCEPROP 2 LAST CDS_LIB standard
J 0
(2300 3050);
DISPLAY INVISIBLE (2300 3050);
FORCEPROP 1 LAST BODY_TYPE PLUMBING
J 0
(2300 3100);
DISPLAY 0.872340 (2300 3100);
PAINT GREEN (2300 3100);
DISPLAY INVISIBLE (2300 3100);
FORCEPROP 1 LAST HDL_TAP TRUE
J 0
(2625 2925);
DISPLAY 0.872340 (2625 2925);
DISPLAY INVISIBLE (2625 2925);
FORCEPROP 1 LAST PATH I143
J 0
(2298 3050);
DISPLAY 0.872340 (2298 3050);
PAINT GREEN (2298 3050);
DISPLAY INVISIBLE (2298 3050);
FORCEADD TAP..1
(2300 2950);
FORCEPROP 3 LASTPIN (2250 2950) SIG_NAME M_C_CPU0_SB_DQS_DP<7>
J 0
(2260 2960);
DISPLAY 0.659574 (2260 2960);
PAINT MONO (2260 2960);
DISPLAY INVISIBLE (2260 2960);
FORCEPROP 1 LASTPIN (2250 2950) BN 7
J 0
(2238 2958);
DISPLAY 0.680851 (2238 2958);
PAINT GREEN (2238 2958);
FORCEPROP 2 LAST CDS_LIB standard
J 0
(2300 2950);
DISPLAY INVISIBLE (2300 2950);
FORCEPROP 1 LAST BODY_TYPE PLUMBING
J 0
(2300 3000);
DISPLAY 0.872340 (2300 3000);
PAINT GREEN (2300 3000);
DISPLAY INVISIBLE (2300 3000);
FORCEPROP 1 LAST HDL_TAP TRUE
J 0
(2625 2825);
DISPLAY 0.872340 (2625 2825);
DISPLAY INVISIBLE (2625 2825);
FORCEPROP 1 LAST PATH I144
J 0
(2298 2950);
DISPLAY 0.872340 (2298 2950);
PAINT GREEN (2298 2950);
DISPLAY INVISIBLE (2298 2950);
FORCEADD TAP..1
(2475 2900);
FORCEPROP 3 LASTPIN (2425 2900) SIG_NAME M_C_CPU0_SB_DQS_DN<7>
J 0
(2435 2910);
DISPLAY 0.659574 (2435 2910);
PAINT MONO (2435 2910);
DISPLAY INVISIBLE (2435 2910);
FORCEPROP 1 LASTPIN (2425 2900) BN 7
J 0
(2413 2908);
DISPLAY 0.680851 (2413 2908);
PAINT GREEN (2413 2908);
FORCEPROP 2 LAST CDS_LIB standard
J 0
(2475 2900);
DISPLAY INVISIBLE (2475 2900);
FORCEPROP 1 LAST BODY_TYPE PLUMBING
J 0
(2475 2950);
DISPLAY 0.872340 (2475 2950);
PAINT GREEN (2475 2950);
DISPLAY INVISIBLE (2475 2950);
FORCEPROP 1 LAST HDL_TAP TRUE
J 0
(2800 2775);
DISPLAY 0.872340 (2800 2775);
DISPLAY INVISIBLE (2800 2775);
FORCEPROP 1 LAST PATH I145
J 0
(2473 2900);
DISPLAY 0.872340 (2473 2900);
PAINT GREEN (2473 2900);
DISPLAY INVISIBLE (2473 2900);
FORCEADD TAP..1
(2475 3000);
FORCEPROP 3 LASTPIN (2425 3000) SIG_NAME M_C_CPU0_SB_DQS_DN<8>
J 0
(2435 3010);
DISPLAY 0.659574 (2435 3010);
PAINT MONO (2435 3010);
DISPLAY INVISIBLE (2435 3010);
FORCEPROP 1 LASTPIN (2425 3000) BN 8
J 0
(2413 3008);
DISPLAY 0.680851 (2413 3008);
PAINT GREEN (2413 3008);
FORCEPROP 2 LAST CDS_LIB standard
J 0
(2475 3000);
DISPLAY INVISIBLE (2475 3000);
FORCEPROP 1 LAST BODY_TYPE PLUMBING
J 0
(2475 3050);
DISPLAY 0.872340 (2475 3050);
PAINT GREEN (2475 3050);
DISPLAY INVISIBLE (2475 3050);
FORCEPROP 1 LAST HDL_TAP TRUE
J 0
(2800 2875);
DISPLAY 0.872340 (2800 2875);
DISPLAY INVISIBLE (2800 2875);
FORCEPROP 1 LAST PATH I146
J 0
(2473 3000);
DISPLAY 0.872340 (2473 3000);
PAINT GREEN (2473 3000);
DISPLAY INVISIBLE (2473 3000);
FORCEADD TAP..1
(2475 3100);
FORCEPROP 3 LASTPIN (2425 3100) SIG_NAME M_C_CPU0_SB_DQS_DN<9>
J 0
(2435 3110);
DISPLAY 0.659574 (2435 3110);
PAINT MONO (2435 3110);
DISPLAY INVISIBLE (2435 3110);
FORCEPROP 1 LASTPIN (2425 3100) BN 9
J 0
(2413 3108);
DISPLAY 0.680851 (2413 3108);
PAINT GREEN (2413 3108);
FORCEPROP 2 LAST CDS_LIB standard
J 0
(2475 3100);
DISPLAY INVISIBLE (2475 3100);
FORCEPROP 1 LAST BODY_TYPE PLUMBING
J 0
(2475 3150);
DISPLAY 0.872340 (2475 3150);
PAINT GREEN (2475 3150);
DISPLAY INVISIBLE (2475 3150);
FORCEPROP 1 LAST HDL_TAP TRUE
J 0
(2800 2975);
DISPLAY 0.872340 (2800 2975);
DISPLAY INVISIBLE (2800 2975);
FORCEPROP 1 LAST PATH I147
J 0
(2473 3100);
DISPLAY 0.872340 (2473 3100);
PAINT GREEN (2473 3100);
DISPLAY INVISIBLE (2473 3100);
FORCEADD TAP..1
(2300 3300);
FORCEPROP 3 LASTPIN (2250 3300) SIG_NAME M_C_CPU0_SA_DQS_DP<0>
J 0
(2260 3310);
DISPLAY 0.659574 (2260 3310);
PAINT MONO (2260 3310);
DISPLAY INVISIBLE (2260 3310);
FORCEPROP 1 LASTPIN (2250 3300) BN 0
J 0
(2238 3308);
DISPLAY 0.680851 (2238 3308);
PAINT GREEN (2238 3308);
FORCEPROP 2 LAST CDS_LIB standard
J 0
(2300 3300);
PAINT MONO (2300 3300);
DISPLAY INVISIBLE (2300 3300);
FORCEPROP 1 LAST BODY_TYPE PLUMBING
J 0
(2300 3350);
DISPLAY 0.872340 (2300 3350);
PAINT GREEN (2300 3350);
DISPLAY INVISIBLE (2300 3350);
FORCEPROP 1 LAST HDL_TAP TRUE
J 0
(2625 3175);
DISPLAY 0.872340 (2625 3175);
DISPLAY INVISIBLE (2625 3175);
FORCEPROP 1 LAST PATH I148
J 0
(2298 3300);
DISPLAY 0.872340 (2298 3300);
PAINT GREEN (2298 3300);
DISPLAY INVISIBLE (2298 3300);
FORCEADD TAP..1
(2300 3150);
FORCEPROP 3 LASTPIN (2250 3150) SIG_NAME M_C_CPU0_SB_DQS_DP<9>
J 0
(2260 3160);
DISPLAY 0.659574 (2260 3160);
PAINT MONO (2260 3160);
DISPLAY INVISIBLE (2260 3160);
FORCEPROP 1 LASTPIN (2250 3150) BN 9
J 0
(2238 3158);
DISPLAY 0.680851 (2238 3158);
PAINT GREEN (2238 3158);
FORCEPROP 2 LAST CDS_LIB standard
J 0
(2300 3150);
DISPLAY INVISIBLE (2300 3150);
FORCEPROP 1 LAST BODY_TYPE PLUMBING
J 0
(2300 3200);
DISPLAY 0.872340 (2300 3200);
PAINT GREEN (2300 3200);
DISPLAY INVISIBLE (2300 3200);
FORCEPROP 1 LAST HDL_TAP TRUE
J 0
(2625 3025);
DISPLAY 0.872340 (2625 3025);
DISPLAY INVISIBLE (2625 3025);
FORCEPROP 1 LAST PATH I149
J 0
(2298 3150);
DISPLAY 0.872340 (2298 3150);
PAINT GREEN (2298 3150);
DISPLAY INVISIBLE (2298 3150);
FORCEADD OFFPAGE..1
(-3025 3200);
FORCEPROP 2 LAST $XR0 22 
J 0
(-3246 3200);
DISPLAY 0.638298 (-3246 3200);
PAINT MONO (-3246 3200);
FORCEPROP 2 LAST CDS_LIB standard
J 0
(-3025 3200);
PAINT MONO (-3025 3200);
DISPLAY INVISIBLE (-3025 3200);
FORCEPROP 1 LAST OFFPAGE TRUE
J 0
(-2700 3075);
DISPLAY 0.872340 (-2700 3075);
DISPLAY INVISIBLE (-2700 3075);
FORCEPROP 1 LAST COMMENT_BODY TRUE
J 0
(-2900 3100);
DISPLAY 0.872340 (-2900 3100);
PAINT GREEN (-2900 3100);
DISPLAY INVISIBLE (-2900 3100);
FORCEPROP 2 LAST PATH I15
J 0
(-2975 3275);
DISPLAY 1.021277 (-2975 3275);
DISPLAY INVISIBLE (-2975 3275);
FORCEADD TAP..1
(2475 3350);
FORCEPROP 3 LASTPIN (2425 3350) SIG_NAME M_C_CPU0_SA_DQS_DN<1>
J 0
(2435 3360);
DISPLAY 0.659574 (2435 3360);
PAINT MONO (2435 3360);
DISPLAY INVISIBLE (2435 3360);
FORCEPROP 1 LASTPIN (2425 3350) BN 1
J 0
(2413 3358);
DISPLAY 0.680851 (2413 3358);
PAINT GREEN (2413 3358);
FORCEPROP 2 LAST CDS_LIB standard
J 0
(2475 3350);
DISPLAY INVISIBLE (2475 3350);
FORCEPROP 1 LAST BODY_TYPE PLUMBING
J 0
(2475 3400);
DISPLAY 0.872340 (2475 3400);
PAINT GREEN (2475 3400);
DISPLAY INVISIBLE (2475 3400);
FORCEPROP 1 LAST HDL_TAP TRUE
J 0
(2800 3225);
DISPLAY 0.872340 (2800 3225);
DISPLAY INVISIBLE (2800 3225);
FORCEPROP 1 LAST PATH I150
J 0
(2473 3350);
DISPLAY 0.872340 (2473 3350);
PAINT GREEN (2473 3350);
DISPLAY INVISIBLE (2473 3350);
FORCEADD TAP..1
(2475 3250);
FORCEPROP 3 LASTPIN (2425 3250) SIG_NAME M_C_CPU0_SA_DQS_DN<0>
J 0
(2435 3260);
DISPLAY 0.659574 (2435 3260);
PAINT MONO (2435 3260);
DISPLAY INVISIBLE (2435 3260);
FORCEPROP 1 LASTPIN (2425 3250) BN 0
J 0
(2413 3258);
DISPLAY 0.680851 (2413 3258);
PAINT GREEN (2413 3258);
FORCEPROP 2 LAST CDS_LIB standard
J 0
(2475 3250);
PAINT MONO (2475 3250);
DISPLAY INVISIBLE (2475 3250);
FORCEPROP 1 LAST BODY_TYPE PLUMBING
J 0
(2475 3300);
DISPLAY 0.872340 (2475 3300);
PAINT GREEN (2475 3300);
DISPLAY INVISIBLE (2475 3300);
FORCEPROP 1 LAST HDL_TAP TRUE
J 0
(2800 3125);
DISPLAY 0.872340 (2800 3125);
DISPLAY INVISIBLE (2800 3125);
FORCEPROP 1 LAST PATH I151
J 0
(2473 3250);
DISPLAY 0.872340 (2473 3250);
PAINT GREEN (2473 3250);
DISPLAY INVISIBLE (2473 3250);
FORCEADD TAP..1
(2300 3500);
FORCEPROP 3 LASTPIN (2250 3500) SIG_NAME M_C_CPU0_SA_DQS_DP<2>
J 0
(2260 3510);
DISPLAY 0.659574 (2260 3510);
PAINT MONO (2260 3510);
DISPLAY INVISIBLE (2260 3510);
FORCEPROP 1 LASTPIN (2250 3500) BN 2
J 0
(2238 3508);
DISPLAY 0.680851 (2238 3508);
PAINT GREEN (2238 3508);
FORCEPROP 2 LAST CDS_LIB standard
J 0
(2300 3500);
DISPLAY INVISIBLE (2300 3500);
FORCEPROP 1 LAST BODY_TYPE PLUMBING
J 0
(2300 3550);
DISPLAY 0.872340 (2300 3550);
PAINT GREEN (2300 3550);
DISPLAY INVISIBLE (2300 3550);
FORCEPROP 1 LAST HDL_TAP TRUE
J 0
(2625 3375);
DISPLAY 0.872340 (2625 3375);
DISPLAY INVISIBLE (2625 3375);
FORCEPROP 1 LAST PATH I152
J 0
(2298 3500);
DISPLAY 0.872340 (2298 3500);
PAINT GREEN (2298 3500);
DISPLAY INVISIBLE (2298 3500);
FORCEADD TAP..1
(2300 3400);
FORCEPROP 3 LASTPIN (2250 3400) SIG_NAME M_C_CPU0_SA_DQS_DP<1>
J 0
(2260 3410);
DISPLAY 0.659574 (2260 3410);
PAINT MONO (2260 3410);
DISPLAY INVISIBLE (2260 3410);
FORCEPROP 1 LASTPIN (2250 3400) BN 1
J 0
(2238 3408);
DISPLAY 0.680851 (2238 3408);
PAINT GREEN (2238 3408);
FORCEPROP 2 LAST CDS_LIB standard
J 0
(2300 3400);
DISPLAY INVISIBLE (2300 3400);
FORCEPROP 1 LAST BODY_TYPE PLUMBING
J 0
(2300 3450);
DISPLAY 0.872340 (2300 3450);
PAINT GREEN (2300 3450);
DISPLAY INVISIBLE (2300 3450);
FORCEPROP 1 LAST HDL_TAP TRUE
J 0
(2625 3275);
DISPLAY 0.872340 (2625 3275);
DISPLAY INVISIBLE (2625 3275);
FORCEPROP 1 LAST PATH I153
J 0
(2298 3400);
DISPLAY 0.872340 (2298 3400);
PAINT GREEN (2298 3400);
DISPLAY INVISIBLE (2298 3400);
FORCEADD TAP..1
(2300 3600);
FORCEPROP 3 LASTPIN (2250 3600) SIG_NAME M_C_CPU0_SA_DQS_DP<3>
J 0
(2260 3610);
DISPLAY 0.659574 (2260 3610);
PAINT MONO (2260 3610);
DISPLAY INVISIBLE (2260 3610);
FORCEPROP 1 LASTPIN (2250 3600) BN 3
J 0
(2238 3608);
DISPLAY 0.680851 (2238 3608);
PAINT GREEN (2238 3608);
FORCEPROP 2 LAST CDS_LIB standard
J 0
(2300 3600);
PAINT MONO (2300 3600);
DISPLAY INVISIBLE (2300 3600);
FORCEPROP 1 LAST BODY_TYPE PLUMBING
J 0
(2300 3650);
DISPLAY 0.872340 (2300 3650);
PAINT GREEN (2300 3650);
DISPLAY INVISIBLE (2300 3650);
FORCEPROP 1 LAST HDL_TAP TRUE
J 0
(2625 3475);
DISPLAY 0.872340 (2625 3475);
DISPLAY INVISIBLE (2625 3475);
FORCEPROP 1 LAST PATH I154
J 0
(2298 3600);
DISPLAY 0.872340 (2298 3600);
PAINT GREEN (2298 3600);
DISPLAY INVISIBLE (2298 3600);
FORCEADD TAP..1
(2475 3450);
FORCEPROP 3 LASTPIN (2425 3450) SIG_NAME M_C_CPU0_SA_DQS_DN<2>
J 0
(2435 3460);
DISPLAY 0.659574 (2435 3460);
PAINT MONO (2435 3460);
DISPLAY INVISIBLE (2435 3460);
FORCEPROP 1 LASTPIN (2425 3450) BN 2
J 0
(2413 3458);
DISPLAY 0.680851 (2413 3458);
PAINT GREEN (2413 3458);
FORCEPROP 2 LAST CDS_LIB standard
J 0
(2475 3450);
DISPLAY INVISIBLE (2475 3450);
FORCEPROP 1 LAST BODY_TYPE PLUMBING
J 0
(2475 3500);
DISPLAY 0.872340 (2475 3500);
PAINT GREEN (2475 3500);
DISPLAY INVISIBLE (2475 3500);
FORCEPROP 1 LAST HDL_TAP TRUE
J 0
(2800 3325);
DISPLAY 0.872340 (2800 3325);
DISPLAY INVISIBLE (2800 3325);
FORCEPROP 1 LAST PATH I155
J 0
(2473 3450);
DISPLAY 0.872340 (2473 3450);
PAINT GREEN (2473 3450);
DISPLAY INVISIBLE (2473 3450);
FORCEADD TAP..1
(2475 3550);
FORCEPROP 3 LASTPIN (2425 3550) SIG_NAME M_C_CPU0_SA_DQS_DN<3>
J 0
(2435 3560);
DISPLAY 0.659574 (2435 3560);
PAINT MONO (2435 3560);
DISPLAY INVISIBLE (2435 3560);
FORCEPROP 1 LASTPIN (2425 3550) BN 3
J 0
(2413 3558);
DISPLAY 0.680851 (2413 3558);
PAINT GREEN (2413 3558);
FORCEPROP 2 LAST CDS_LIB standard
J 0
(2475 3550);
PAINT MONO (2475 3550);
DISPLAY INVISIBLE (2475 3550);
FORCEPROP 1 LAST BODY_TYPE PLUMBING
J 0
(2475 3600);
DISPLAY 0.872340 (2475 3600);
PAINT GREEN (2475 3600);
DISPLAY INVISIBLE (2475 3600);
FORCEPROP 1 LAST HDL_TAP TRUE
J 0
(2800 3425);
DISPLAY 0.872340 (2800 3425);
DISPLAY INVISIBLE (2800 3425);
FORCEPROP 1 LAST PATH I156
J 0
(2473 3550);
DISPLAY 0.872340 (2473 3550);
PAINT GREEN (2473 3550);
DISPLAY INVISIBLE (2473 3550);
FORCEADD TAP..1
(2300 3700);
FORCEPROP 3 LASTPIN (2250 3700) SIG_NAME M_C_CPU0_SA_DQS_DP<4>
J 0
(2260 3710);
DISPLAY 0.659574 (2260 3710);
PAINT MONO (2260 3710);
DISPLAY INVISIBLE (2260 3710);
FORCEPROP 1 LASTPIN (2250 3700) BN 4
J 0
(2238 3708);
DISPLAY 0.680851 (2238 3708);
PAINT GREEN (2238 3708);
FORCEPROP 2 LAST CDS_LIB standard
J 0
(2300 3700);
PAINT MONO (2300 3700);
DISPLAY INVISIBLE (2300 3700);
FORCEPROP 1 LAST BODY_TYPE PLUMBING
J 0
(2300 3750);
DISPLAY 0.872340 (2300 3750);
PAINT GREEN (2300 3750);
DISPLAY INVISIBLE (2300 3750);
FORCEPROP 1 LAST HDL_TAP TRUE
J 0
(2625 3575);
DISPLAY 0.872340 (2625 3575);
DISPLAY INVISIBLE (2625 3575);
FORCEPROP 1 LAST PATH I157
J 0
(2298 3700);
DISPLAY 0.872340 (2298 3700);
PAINT GREEN (2298 3700);
DISPLAY INVISIBLE (2298 3700);
FORCEADD TAP..1
(2300 3800);
FORCEPROP 3 LASTPIN (2250 3800) SIG_NAME M_C_CPU0_SA_DQS_DP<5>
J 0
(2260 3810);
DISPLAY 0.659574 (2260 3810);
PAINT MONO (2260 3810);
DISPLAY INVISIBLE (2260 3810);
FORCEPROP 1 LASTPIN (2250 3800) BN 5
J 0
(2238 3808);
DISPLAY 0.680851 (2238 3808);
PAINT GREEN (2238 3808);
FORCEPROP 2 LAST CDS_LIB standard
J 0
(2300 3800);
DISPLAY INVISIBLE (2300 3800);
FORCEPROP 1 LAST BODY_TYPE PLUMBING
J 0
(2300 3850);
DISPLAY 0.872340 (2300 3850);
PAINT GREEN (2300 3850);
DISPLAY INVISIBLE (2300 3850);
FORCEPROP 1 LAST HDL_TAP TRUE
J 0
(2625 3675);
DISPLAY 0.872340 (2625 3675);
DISPLAY INVISIBLE (2625 3675);
FORCEPROP 1 LAST PATH I158
J 0
(2298 3800);
DISPLAY 0.872340 (2298 3800);
PAINT GREEN (2298 3800);
DISPLAY INVISIBLE (2298 3800);
FORCEADD TAP..1
(2475 3850);
FORCEPROP 3 LASTPIN (2425 3850) SIG_NAME M_C_CPU0_SA_DQS_DN<6>
J 0
(2435 3860);
DISPLAY 0.659574 (2435 3860);
PAINT MONO (2435 3860);
DISPLAY INVISIBLE (2435 3860);
FORCEPROP 1 LASTPIN (2425 3850) BN 6
J 0
(2413 3858);
DISPLAY 0.680851 (2413 3858);
PAINT GREEN (2413 3858);
FORCEPROP 2 LAST CDS_LIB standard
J 0
(2475 3850);
DISPLAY INVISIBLE (2475 3850);
FORCEPROP 1 LAST BODY_TYPE PLUMBING
J 0
(2475 3900);
DISPLAY 0.872340 (2475 3900);
PAINT GREEN (2475 3900);
DISPLAY INVISIBLE (2475 3900);
FORCEPROP 1 LAST HDL_TAP TRUE
J 0
(2800 3725);
DISPLAY 0.872340 (2800 3725);
DISPLAY INVISIBLE (2800 3725);
FORCEPROP 1 LAST PATH I159
J 0
(2473 3850);
DISPLAY 0.872340 (2473 3850);
PAINT GREEN (2473 3850);
DISPLAY INVISIBLE (2473 3850);
FORCEADD OFFPAGE..1
(-3025 3250);
FORCEPROP 2 LAST $XR0 22 
J 0
(-3246 3250);
DISPLAY 0.638298 (-3246 3250);
PAINT MONO (-3246 3250);
FORCEPROP 2 LAST CDS_LIB standard
J 0
(-3025 3250);
PAINT MONO (-3025 3250);
DISPLAY INVISIBLE (-3025 3250);
FORCEPROP 1 LAST OFFPAGE TRUE
J 0
(-2700 3125);
DISPLAY 0.872340 (-2700 3125);
DISPLAY INVISIBLE (-2700 3125);
FORCEPROP 1 LAST COMMENT_BODY TRUE
J 0
(-2900 3150);
DISPLAY 0.872340 (-2900 3150);
PAINT GREEN (-2900 3150);
DISPLAY INVISIBLE (-2900 3150);
FORCEPROP 2 LAST PATH I16
J 0
(-2975 3325);
DISPLAY 1.021277 (-2975 3325);
DISPLAY INVISIBLE (-2975 3325);
FORCEADD TAP..1
(2475 3750);
FORCEPROP 3 LASTPIN (2425 3750) SIG_NAME M_C_CPU0_SA_DQS_DN<5>
J 0
(2435 3760);
DISPLAY 0.659574 (2435 3760);
PAINT MONO (2435 3760);
DISPLAY INVISIBLE (2435 3760);
FORCEPROP 1 LASTPIN (2425 3750) BN 5
J 0
(2413 3758);
DISPLAY 0.680851 (2413 3758);
PAINT GREEN (2413 3758);
FORCEPROP 2 LAST CDS_LIB standard
J 0
(2475 3750);
DISPLAY INVISIBLE (2475 3750);
FORCEPROP 1 LAST BODY_TYPE PLUMBING
J 0
(2475 3800);
DISPLAY 0.872340 (2475 3800);
PAINT GREEN (2475 3800);
DISPLAY INVISIBLE (2475 3800);
FORCEPROP 1 LAST HDL_TAP TRUE
J 0
(2800 3625);
DISPLAY 0.872340 (2800 3625);
DISPLAY INVISIBLE (2800 3625);
FORCEPROP 1 LAST PATH I160
J 0
(2473 3750);
DISPLAY 0.872340 (2473 3750);
PAINT GREEN (2473 3750);
DISPLAY INVISIBLE (2473 3750);
FORCEADD TAP..1
(2475 3650);
FORCEPROP 3 LASTPIN (2425 3650) SIG_NAME M_C_CPU0_SA_DQS_DN<4>
J 0
(2435 3660);
DISPLAY 0.659574 (2435 3660);
PAINT MONO (2435 3660);
DISPLAY INVISIBLE (2435 3660);
FORCEPROP 1 LASTPIN (2425 3650) BN 4
J 0
(2413 3658);
DISPLAY 0.680851 (2413 3658);
PAINT GREEN (2413 3658);
FORCEPROP 2 LAST CDS_LIB standard
J 0
(2475 3650);
PAINT MONO (2475 3650);
DISPLAY INVISIBLE (2475 3650);
FORCEPROP 1 LAST BODY_TYPE PLUMBING
J 0
(2475 3700);
DISPLAY 0.872340 (2475 3700);
PAINT GREEN (2475 3700);
DISPLAY INVISIBLE (2475 3700);
FORCEPROP 1 LAST HDL_TAP TRUE
J 0
(2800 3525);
DISPLAY 0.872340 (2800 3525);
DISPLAY INVISIBLE (2800 3525);
FORCEPROP 1 LAST PATH I161
J 0
(2473 3650);
DISPLAY 0.872340 (2473 3650);
PAINT GREEN (2473 3650);
DISPLAY INVISIBLE (2473 3650);
FORCEADD OFFPAGE..2
(3425 3125);
FORCEPROP 2 LAST $XR1 86 
J 0
(3704 3125);
DISPLAY 0.638298 (3704 3125);
PAINT MONO (3704 3125);
FORCEPROP 2 LAST $XR0 22 
J 0
(3614 3125);
DISPLAY 0.638298 (3614 3125);
PAINT MONO (3614 3125);
FORCEPROP 2 LAST CDS_LIB standard
J 0
(3425 3125);
PAINT MONO (3425 3125);
DISPLAY INVISIBLE (3425 3125);
FORCEPROP 1 LAST OFFPAGE TRUE
J 0
(3750 3000);
DISPLAY 1.170213 (3750 3000);
PAINT GREEN (3750 3000);
DISPLAY INVISIBLE (3750 3000);
FORCEPROP 1 LAST COMMENT_BODY TRUE
J 0
(3380 3030);
DISPLAY 1.170213 (3380 3030);
PAINT GREEN (3380 3030);
DISPLAY INVISIBLE (3380 3030);
FORCEPROP 2 LAST PATH I162
J 0
(3600 3200);
DISPLAY 1.021277 (3600 3200);
DISPLAY INVISIBLE (3600 3200);
FORCEADD OFFPAGE..2
(3425 3175);
FORCEPROP 2 LAST $XR1 86 
J 0
(3704 3175);
DISPLAY 0.638298 (3704 3175);
PAINT MONO (3704 3175);
FORCEPROP 2 LAST $XR0 22 
J 0
(3614 3175);
DISPLAY 0.638298 (3614 3175);
PAINT MONO (3614 3175);
FORCEPROP 2 LAST CDS_LIB standard
J 0
(3425 3175);
PAINT MONO (3425 3175);
DISPLAY INVISIBLE (3425 3175);
FORCEPROP 1 LAST OFFPAGE TRUE
J 0
(3750 3050);
DISPLAY 1.170213 (3750 3050);
PAINT GREEN (3750 3050);
DISPLAY INVISIBLE (3750 3050);
FORCEPROP 1 LAST COMMENT_BODY TRUE
J 0
(3380 3080);
DISPLAY 1.170213 (3380 3080);
PAINT GREEN (3380 3080);
DISPLAY INVISIBLE (3380 3080);
FORCEPROP 2 LAST PATH I163
J 0
(3600 3250);
DISPLAY 1.021277 (3600 3250);
DISPLAY INVISIBLE (3600 3250);
FORCEADD OFFPAGE..3
(375 4225);
FORCEPROP 2 LAST $XR1 86 
J 0
(679 4225);
DISPLAY 0.638298 (679 4225);
PAINT MONO (679 4225);
FORCEPROP 2 LAST $XR0 22 
J 0
(589 4225);
DISPLAY 0.638298 (589 4225);
PAINT MONO (589 4225);
FORCEPROP 2 LAST CDS_LIB standard
J 2
(375 4225);
DISPLAY INVISIBLE (375 4225);
FORCEPROP 1 LAST OFFPAGE TRUE
J 0
(700 4100);
DISPLAY 0.872340 (700 4100);
DISPLAY INVISIBLE (700 4100);
FORCEPROP 1 LAST COMMENT_BODY TRUE
J 0
(325 4125);
DISPLAY 0.872340 (325 4125);
PAINT GREEN (325 4125);
DISPLAY INVISIBLE (325 4125);
FORCEPROP 2 LAST PATH I164
J 0
(575 4300);
DISPLAY 1.021277 (575 4300);
DISPLAY INVISIBLE (575 4300);
FORCEADD TAP..1
(2300 4000);
FORCEPROP 3 LASTPIN (2250 4000) SIG_NAME M_C_CPU0_SA_DQS_DP<7>
J 0
(2260 4010);
DISPLAY 0.659574 (2260 4010);
PAINT MONO (2260 4010);
DISPLAY INVISIBLE (2260 4010);
FORCEPROP 1 LASTPIN (2250 4000) BN 7
J 0
(2238 4008);
DISPLAY 0.680851 (2238 4008);
PAINT GREEN (2238 4008);
FORCEPROP 2 LAST CDS_LIB standard
J 0
(2300 4000);
DISPLAY INVISIBLE (2300 4000);
FORCEPROP 1 LAST BODY_TYPE PLUMBING
J 0
(2300 4050);
DISPLAY 0.872340 (2300 4050);
PAINT GREEN (2300 4050);
DISPLAY INVISIBLE (2300 4050);
FORCEPROP 1 LAST HDL_TAP TRUE
J 0
(2625 3875);
DISPLAY 0.872340 (2625 3875);
DISPLAY INVISIBLE (2625 3875);
FORCEPROP 1 LAST PATH I165
J 0
(2298 4000);
DISPLAY 0.872340 (2298 4000);
PAINT GREEN (2298 4000);
DISPLAY INVISIBLE (2298 4000);
FORCEADD TAP..1
(2300 3900);
FORCEPROP 3 LASTPIN (2250 3900) SIG_NAME M_C_CPU0_SA_DQS_DP<6>
J 0
(2260 3910);
DISPLAY 0.659574 (2260 3910);
PAINT MONO (2260 3910);
DISPLAY INVISIBLE (2260 3910);
FORCEPROP 1 LASTPIN (2250 3900) BN 6
J 0
(2238 3908);
DISPLAY 0.680851 (2238 3908);
PAINT GREEN (2238 3908);
FORCEPROP 2 LAST CDS_LIB standard
J 0
(2300 3900);
DISPLAY INVISIBLE (2300 3900);
FORCEPROP 1 LAST BODY_TYPE PLUMBING
J 0
(2300 3950);
DISPLAY 0.872340 (2300 3950);
PAINT GREEN (2300 3950);
DISPLAY INVISIBLE (2300 3950);
FORCEPROP 1 LAST HDL_TAP TRUE
J 0
(2625 3775);
DISPLAY 0.872340 (2625 3775);
DISPLAY INVISIBLE (2625 3775);
FORCEPROP 1 LAST PATH I166
J 0
(2298 3900);
DISPLAY 0.872340 (2298 3900);
PAINT GREEN (2298 3900);
DISPLAY INVISIBLE (2298 3900);
FORCEADD TAP..1
(2300 4100);
FORCEPROP 3 LASTPIN (2250 4100) SIG_NAME M_C_CPU0_SA_DQS_DP<8>
J 0
(2260 4110);
DISPLAY 0.659574 (2260 4110);
PAINT MONO (2260 4110);
DISPLAY INVISIBLE (2260 4110);
FORCEPROP 1 LASTPIN (2250 4100) BN 8
J 0
(2238 4108);
DISPLAY 0.680851 (2238 4108);
PAINT GREEN (2238 4108);
FORCEPROP 2 LAST CDS_LIB standard
J 0
(2300 4100);
DISPLAY INVISIBLE (2300 4100);
FORCEPROP 1 LAST BODY_TYPE PLUMBING
J 0
(2300 4150);
DISPLAY 0.872340 (2300 4150);
PAINT GREEN (2300 4150);
DISPLAY INVISIBLE (2300 4150);
FORCEPROP 1 LAST HDL_TAP TRUE
J 0
(2625 3975);
DISPLAY 0.872340 (2625 3975);
DISPLAY INVISIBLE (2625 3975);
FORCEPROP 1 LAST PATH I167
J 0
(2298 4100);
DISPLAY 0.872340 (2298 4100);
PAINT GREEN (2298 4100);
DISPLAY INVISIBLE (2298 4100);
FORCEADD TAP..1
(2475 3950);
FORCEPROP 3 LASTPIN (2425 3950) SIG_NAME M_C_CPU0_SA_DQS_DN<7>
J 0
(2435 3960);
DISPLAY 0.659574 (2435 3960);
PAINT MONO (2435 3960);
DISPLAY INVISIBLE (2435 3960);
FORCEPROP 1 LASTPIN (2425 3950) BN 7
J 0
(2413 3958);
DISPLAY 0.680851 (2413 3958);
PAINT GREEN (2413 3958);
FORCEPROP 2 LAST CDS_LIB standard
J 0
(2475 3950);
DISPLAY INVISIBLE (2475 3950);
FORCEPROP 1 LAST BODY_TYPE PLUMBING
J 0
(2475 4000);
DISPLAY 0.872340 (2475 4000);
PAINT GREEN (2475 4000);
DISPLAY INVISIBLE (2475 4000);
FORCEPROP 1 LAST HDL_TAP TRUE
J 0
(2800 3825);
DISPLAY 0.872340 (2800 3825);
DISPLAY INVISIBLE (2800 3825);
FORCEPROP 1 LAST PATH I168
J 0
(2473 3950);
DISPLAY 0.872340 (2473 3950);
PAINT GREEN (2473 3950);
DISPLAY INVISIBLE (2473 3950);
FORCEADD TAP..1
(2475 4150);
FORCEPROP 3 LASTPIN (2425 4150) SIG_NAME M_C_CPU0_SA_DQS_DN<9>
J 0
(2435 4160);
DISPLAY 0.659574 (2435 4160);
PAINT MONO (2435 4160);
DISPLAY INVISIBLE (2435 4160);
FORCEPROP 1 LASTPIN (2425 4150) BN 9
J 0
(2413 4158);
DISPLAY 0.680851 (2413 4158);
PAINT GREEN (2413 4158);
FORCEPROP 2 LAST CDS_LIB standard
J 0
(2475 4150);
DISPLAY INVISIBLE (2475 4150);
FORCEPROP 1 LAST BODY_TYPE PLUMBING
J 0
(2475 4200);
DISPLAY 0.872340 (2475 4200);
PAINT GREEN (2475 4200);
DISPLAY INVISIBLE (2475 4200);
FORCEPROP 1 LAST HDL_TAP TRUE
J 0
(2800 4025);
DISPLAY 0.872340 (2800 4025);
DISPLAY INVISIBLE (2800 4025);
FORCEPROP 1 LAST PATH I169
J 0
(2473 4150);
DISPLAY 0.872340 (2473 4150);
PAINT GREEN (2473 4150);
DISPLAY INVISIBLE (2473 4150);
FORCEADD OFFPAGE..1
(-3025 3350);
FORCEPROP 2 LAST $XR1 86 
J 0
(-3336 3350);
DISPLAY 0.638298 (-3336 3350);
PAINT MONO (-3336 3350);
FORCEPROP 2 LAST $XR0 22 
J 0
(-3246 3350);
DISPLAY 0.638298 (-3246 3350);
PAINT MONO (-3246 3350);
FORCEPROP 2 LAST CDS_LIB standard
J 0
(-3025 3350);
PAINT MONO (-3025 3350);
DISPLAY INVISIBLE (-3025 3350);
FORCEPROP 1 LAST OFFPAGE TRUE
J 0
(-2700 3225);
DISPLAY 0.872340 (-2700 3225);
DISPLAY INVISIBLE (-2700 3225);
FORCEPROP 1 LAST COMMENT_BODY TRUE
J 0
(-2900 3250);
DISPLAY 0.872340 (-2900 3250);
PAINT GREEN (-2900 3250);
DISPLAY INVISIBLE (-2900 3250);
FORCEPROP 2 LAST PATH I17
J 0
(-2975 3425);
DISPLAY 1.021277 (-2975 3425);
DISPLAY INVISIBLE (-2975 3425);
FORCEADD TAP..1
(2475 4050);
FORCEPROP 3 LASTPIN (2425 4050) SIG_NAME M_C_CPU0_SA_DQS_DN<8>
J 0
(2435 4060);
DISPLAY 0.659574 (2435 4060);
PAINT MONO (2435 4060);
DISPLAY INVISIBLE (2435 4060);
FORCEPROP 1 LASTPIN (2425 4050) BN 8
J 0
(2413 4058);
DISPLAY 0.680851 (2413 4058);
PAINT GREEN (2413 4058);
FORCEPROP 2 LAST CDS_LIB standard
J 0
(2475 4050);
DISPLAY INVISIBLE (2475 4050);
FORCEPROP 1 LAST BODY_TYPE PLUMBING
J 0
(2475 4100);
DISPLAY 0.872340 (2475 4100);
PAINT GREEN (2475 4100);
DISPLAY INVISIBLE (2475 4100);
FORCEPROP 1 LAST HDL_TAP TRUE
J 0
(2800 3925);
DISPLAY 0.872340 (2800 3925);
DISPLAY INVISIBLE (2800 3925);
FORCEPROP 1 LAST PATH I170
J 0
(2473 4050);
DISPLAY 0.872340 (2473 4050);
PAINT GREEN (2473 4050);
DISPLAY INVISIBLE (2473 4050);
FORCEADD TAP..1
(2300 4200);
FORCEPROP 3 LASTPIN (2250 4200) SIG_NAME M_C_CPU0_SA_DQS_DP<9>
J 0
(2260 4210);
DISPLAY 0.659574 (2260 4210);
PAINT MONO (2260 4210);
DISPLAY INVISIBLE (2260 4210);
FORCEPROP 1 LASTPIN (2250 4200) BN 9
J 0
(2238 4208);
DISPLAY 0.680851 (2238 4208);
PAINT GREEN (2238 4208);
FORCEPROP 2 LAST CDS_LIB standard
J 0
(2300 4200);
DISPLAY INVISIBLE (2300 4200);
FORCEPROP 1 LAST BODY_TYPE PLUMBING
J 0
(2300 4250);
DISPLAY 0.872340 (2300 4250);
PAINT GREEN (2300 4250);
DISPLAY INVISIBLE (2300 4250);
FORCEPROP 1 LAST HDL_TAP TRUE
J 0
(2625 4075);
DISPLAY 0.872340 (2625 4075);
DISPLAY INVISIBLE (2625 4075);
FORCEPROP 1 LAST PATH I171
J 0
(2298 4200);
DISPLAY 0.872340 (2298 4200);
PAINT GREEN (2298 4200);
DISPLAY INVISIBLE (2298 4200);
FORCEADD OFFPAGE..2
(3425 4175);
FORCEPROP 2 LAST $XR1 86 
J 0
(3704 4175);
DISPLAY 0.638298 (3704 4175);
PAINT MONO (3704 4175);
FORCEPROP 2 LAST $XR0 22 
J 0
(3614 4175);
DISPLAY 0.638298 (3614 4175);
PAINT MONO (3614 4175);
FORCEPROP 2 LAST CDS_LIB standard
J 0
(3425 4175);
PAINT MONO (3425 4175);
DISPLAY INVISIBLE (3425 4175);
FORCEPROP 1 LAST OFFPAGE TRUE
J 0
(3750 4050);
DISPLAY 1.170213 (3750 4050);
PAINT GREEN (3750 4050);
DISPLAY INVISIBLE (3750 4050);
FORCEPROP 1 LAST COMMENT_BODY TRUE
J 0
(3380 4080);
DISPLAY 1.170213 (3380 4080);
PAINT GREEN (3380 4080);
DISPLAY INVISIBLE (3380 4080);
FORCEPROP 2 LAST PATH I172
J 0
(3600 4250);
DISPLAY 1.021277 (3600 4250);
DISPLAY INVISIBLE (3600 4250);
FORCEADD OFFPAGE..2
(3425 4225);
FORCEPROP 2 LAST $XR1 86 
J 0
(3704 4225);
DISPLAY 0.638298 (3704 4225);
PAINT MONO (3704 4225);
FORCEPROP 2 LAST $XR0 22 
J 0
(3614 4225);
DISPLAY 0.638298 (3614 4225);
PAINT MONO (3614 4225);
FORCEPROP 2 LAST CDS_LIB standard
J 0
(3425 4225);
PAINT MONO (3425 4225);
DISPLAY INVISIBLE (3425 4225);
FORCEPROP 1 LAST OFFPAGE TRUE
J 0
(3750 4100);
DISPLAY 1.170213 (3750 4100);
PAINT GREEN (3750 4100);
DISPLAY INVISIBLE (3750 4100);
FORCEPROP 1 LAST COMMENT_BODY TRUE
J 0
(3380 4130);
DISPLAY 1.170213 (3380 4130);
PAINT GREEN (3380 4130);
DISPLAY INVISIBLE (3380 4130);
FORCEPROP 2 LAST PATH I173
J 0
(3600 4300);
DISPLAY 1.021277 (3600 4300);
DISPLAY INVISIBLE (3600 4300);
FORCEADD VCC_CORE..1
(3975 4750);
FORCEPROP 3 LASTPIN (3975 4700) SIG_NAME P12V_S3_AUX_CPU0_NVDIMM\g
J 0
(3985 4710);
DISPLAY 0.659574 (3985 4710);
PAINT MONO (3985 4710);
DISPLAY INVISIBLE (3985 4710);
FORCEPROP 1 LAST HDL_POWER P12V_S3_AUX_CPU0_NVDIMM
J 1
(3975 4800);
DISPLAY 1.148936 (3975 4800);
PAINT GREEN (3975 4800);
FORCEPROP 2 LAST CDS_LIB logical_power
J 0
(3975 4750);
PAINT MONO (3975 4750);
DISPLAY INVISIBLE (3975 4750);
FORCEPROP 1 LAST PATH I174
J 0
(4025 4775);
DISPLAY 0.872340 (4025 4775);
PAINT AQUA (4025 4775);
DISPLAY INVISIBLE (4025 4775);
FORCEADD SCONN288_ADR50017P087CC..3
(4825 2575);
FORCEPROP 1 LAST PART_NUMBER DFHST8FS460
J 0
(4370 4499);
DISPLAY 0.723404 (4370 4499);
PAINT GREEN (4370 4499);
DISPLAY INVISIBLE (4370 4499);
FORCEPROP 1 LAST MATERIAL IO
J 0
(4370 4372);
DISPLAY 0.723404 (4370 4372);
PAINT GREEN (4370 4372);
FORCEPROP 2 LAST PART_TYPE SMLF
J 0
(4375 4650);
DISPLAY 1.021277 (4375 4650);
FORCEPROP 2 LAST VALUE SCONN288_ADR50017-P087CC
J 0
(4375 4600);
DISPLAY 1.021277 (4375 4600);
FORCEPROP 1 LAST $LOCATION J6
J 0
(4375 4550);
DISPLAY 0.723404 (4375 4550);
PAINT GREEN (4375 4550);
FORCEPROP 0 LASTPIN (5425 950) $PN G1
J 0
(5435 960);
DISPLAY 0.680851 (5435 960);
PAINT MONO (5435 960);
FORCEPROP 0 LASTPIN (5425 900) $PN G2
J 0
(5435 910);
DISPLAY 0.680851 (5435 910);
PAINT MONO (5435 910);
FORCEPROP 0 LASTPIN (5425 850) $PN G3
J 0
(5435 860);
DISPLAY 0.680851 (5435 860);
PAINT MONO (5435 860);
FORCEPROP 0 LASTPIN (4225 4100) $PN 1
J 2
(4215 4110);
DISPLAY 0.680851 (4215 4110);
PAINT MONO (4215 4110);
FORCEPROP 0 LASTPIN (4225 4150) $PN 145
J 2
(4215 4160);
DISPLAY 0.680851 (4215 4160);
PAINT MONO (4215 4160);
FORCEPROP 0 LASTPIN (4225 4200) $PN 146
J 2
(4215 4210);
DISPLAY 0.680851 (4215 4210);
PAINT MONO (4215 4210);
FORCEPROP 0 LASTPIN (5425 1050) $PN 6
J 0
(5435 1060);
DISPLAY 0.680851 (5435 1060);
PAINT MONO (5435 1060);
FORCEPROP 0 LASTPIN (5425 1100) $PN 8
J 0
(5435 1110);
DISPLAY 0.680851 (5435 1110);
PAINT MONO (5435 1110);
FORCEPROP 0 LASTPIN (5425 1150) $PN 10
J 0
(5435 1160);
DISPLAY 0.680851 (5435 1160);
PAINT MONO (5435 1160);
FORCEPROP 0 LASTPIN (5425 1200) $PN 13
J 0
(5435 1210);
DISPLAY 0.680851 (5435 1210);
PAINT MONO (5435 1210);
FORCEPROP 0 LASTPIN (5425 1250) $PN 15
J 0
(5435 1260);
DISPLAY 0.680851 (5435 1260);
PAINT MONO (5435 1260);
FORCEPROP 0 LASTPIN (5425 1300) $PN 17
J 0
(5435 1310);
DISPLAY 0.680851 (5435 1310);
PAINT MONO (5435 1310);
FORCEPROP 0 LASTPIN (5425 1350) $PN 19
J 0
(5435 1360);
DISPLAY 0.680851 (5435 1360);
PAINT MONO (5435 1360);
FORCEPROP 0 LASTPIN (5425 1400) $PN 21
J 0
(5435 1410);
DISPLAY 0.680851 (5435 1410);
PAINT MONO (5435 1410);
FORCEPROP 0 LASTPIN (5425 1450) $PN 24
J 0
(5435 1460);
DISPLAY 0.680851 (5435 1460);
PAINT MONO (5435 1460);
FORCEPROP 0 LASTPIN (5425 1500) $PN 26
J 0
(5435 1510);
DISPLAY 0.680851 (5435 1510);
PAINT MONO (5435 1510);
FORCEPROP 0 LASTPIN (5425 1550) $PN 28
J 0
(5435 1560);
DISPLAY 0.680851 (5435 1560);
PAINT MONO (5435 1560);
FORCEPROP 0 LASTPIN (5425 1600) $PN 30
J 0
(5435 1610);
DISPLAY 0.680851 (5435 1610);
PAINT MONO (5435 1610);
FORCEPROP 0 LASTPIN (5425 1650) $PN 32
J 0
(5435 1660);
DISPLAY 0.680851 (5435 1660);
PAINT MONO (5435 1660);
FORCEPROP 0 LASTPIN (5425 1700) $PN 35
J 0
(5435 1710);
DISPLAY 0.680851 (5435 1710);
PAINT MONO (5435 1710);
FORCEPROP 0 LASTPIN (5425 1750) $PN 37
J 0
(5435 1760);
DISPLAY 0.680851 (5435 1760);
PAINT MONO (5435 1760);
FORCEPROP 0 LASTPIN (5425 1800) $PN 39
J 0
(5435 1810);
DISPLAY 0.680851 (5435 1810);
PAINT MONO (5435 1810);
FORCEPROP 0 LASTPIN (5425 1850) $PN 41
J 0
(5435 1860);
DISPLAY 0.680851 (5435 1860);
PAINT MONO (5435 1860);
FORCEPROP 0 LASTPIN (5425 1900) $PN 43
J 0
(5435 1910);
DISPLAY 0.680851 (5435 1910);
PAINT MONO (5435 1910);
FORCEPROP 0 LASTPIN (5425 1950) $PN 46
J 0
(5435 1960);
DISPLAY 0.680851 (5435 1960);
PAINT MONO (5435 1960);
FORCEPROP 0 LASTPIN (5425 2000) $PN 48
J 0
(5435 2010);
DISPLAY 0.680851 (5435 2010);
PAINT MONO (5435 2010);
FORCEPROP 0 LASTPIN (5425 2050) $PN 50
J 0
(5435 2060);
DISPLAY 0.680851 (5435 2060);
PAINT MONO (5435 2060);
FORCEPROP 0 LASTPIN (5425 2100) $PN 52
J 0
(5435 2110);
DISPLAY 0.680851 (5435 2110);
PAINT MONO (5435 2110);
FORCEPROP 0 LASTPIN (5425 2150) $PN 54
J 0
(5435 2160);
DISPLAY 0.680851 (5435 2160);
PAINT MONO (5435 2160);
FORCEPROP 0 LASTPIN (5425 2200) $PN 57
J 0
(5435 2210);
DISPLAY 0.680851 (5435 2210);
PAINT MONO (5435 2210);
FORCEPROP 0 LASTPIN (5425 2250) $PN 59
J 0
(5435 2260);
DISPLAY 0.680851 (5435 2260);
PAINT MONO (5435 2260);
FORCEPROP 0 LASTPIN (5425 2300) $PN 61
J 0
(5435 2310);
DISPLAY 0.680851 (5435 2310);
PAINT MONO (5435 2310);
FORCEPROP 0 LASTPIN (5425 2350) $PN 63
J 0
(5435 2360);
DISPLAY 0.680851 (5435 2360);
PAINT MONO (5435 2360);
FORCEPROP 0 LASTPIN (5425 2400) $PN 65
J 0
(5435 2410);
DISPLAY 0.680851 (5435 2410);
PAINT MONO (5435 2410);
FORCEPROP 0 LASTPIN (5425 2450) $PN 67
J 0
(5435 2460);
DISPLAY 0.680851 (5435 2460);
PAINT MONO (5435 2460);
FORCEPROP 0 LASTPIN (5425 2500) $PN 69
J 0
(5435 2510);
DISPLAY 0.680851 (5435 2510);
PAINT MONO (5435 2510);
FORCEPROP 0 LASTPIN (5425 2550) $PN 71
J 0
(5435 2560);
DISPLAY 0.680851 (5435 2560);
PAINT MONO (5435 2560);
FORCEPROP 0 LASTPIN (5425 2600) $PN 73
J 0
(5435 2610);
DISPLAY 0.680851 (5435 2610);
PAINT MONO (5435 2610);
FORCEPROP 0 LASTPIN (5425 2650) $PN 75
J 0
(5435 2660);
DISPLAY 0.680851 (5435 2660);
PAINT MONO (5435 2660);
FORCEPROP 0 LASTPIN (5425 2700) $PN 77
J 0
(5435 2710);
DISPLAY 0.680851 (5435 2710);
PAINT MONO (5435 2710);
FORCEPROP 0 LASTPIN (5425 2750) $PN 79
J 0
(5435 2760);
DISPLAY 0.680851 (5435 2760);
PAINT MONO (5435 2760);
FORCEPROP 0 LASTPIN (5425 2800) $PN 81
J 0
(5435 2810);
DISPLAY 0.680851 (5435 2810);
PAINT MONO (5435 2810);
FORCEPROP 0 LASTPIN (5425 2850) $PN 83
J 0
(5435 2860);
DISPLAY 0.680851 (5435 2860);
PAINT MONO (5435 2860);
FORCEPROP 0 LASTPIN (5425 2900) $PN 85
J 0
(5435 2910);
DISPLAY 0.680851 (5435 2910);
PAINT MONO (5435 2910);
FORCEPROP 0 LASTPIN (5425 2950) $PN 88
J 0
(5435 2960);
DISPLAY 0.680851 (5435 2960);
PAINT MONO (5435 2960);
FORCEPROP 0 LASTPIN (5425 3000) $PN 90
J 0
(5435 3010);
DISPLAY 0.680851 (5435 3010);
PAINT MONO (5435 3010);
FORCEPROP 0 LASTPIN (5425 3050) $PN 92
J 0
(5435 3060);
DISPLAY 0.680851 (5435 3060);
PAINT MONO (5435 3060);
FORCEPROP 0 LASTPIN (5425 3100) $PN 95
J 0
(5435 3110);
DISPLAY 0.680851 (5435 3110);
PAINT MONO (5435 3110);
FORCEPROP 0 LASTPIN (5425 3150) $PN 97
J 0
(5435 3160);
DISPLAY 0.680851 (5435 3160);
PAINT MONO (5435 3160);
FORCEPROP 0 LASTPIN (5425 3200) $PN 99
J 0
(5435 3210);
DISPLAY 0.680851 (5435 3210);
PAINT MONO (5435 3210);
FORCEPROP 0 LASTPIN (5425 3250) $PN 101
J 0
(5435 3260);
DISPLAY 0.680851 (5435 3260);
PAINT MONO (5435 3260);
FORCEPROP 0 LASTPIN (5425 3300) $PN 103
J 0
(5435 3310);
DISPLAY 0.680851 (5435 3310);
PAINT MONO (5435 3310);
FORCEPROP 0 LASTPIN (5425 3350) $PN 106
J 0
(5435 3360);
DISPLAY 0.680851 (5435 3360);
PAINT MONO (5435 3360);
FORCEPROP 0 LASTPIN (5425 3400) $PN 108
J 0
(5435 3410);
DISPLAY 0.680851 (5435 3410);
PAINT MONO (5435 3410);
FORCEPROP 0 LASTPIN (5425 3450) $PN 110
J 0
(5435 3460);
DISPLAY 0.680851 (5435 3460);
PAINT MONO (5435 3460);
FORCEPROP 0 LASTPIN (5425 3500) $PN 112
J 0
(5435 3510);
DISPLAY 0.680851 (5435 3510);
PAINT MONO (5435 3510);
FORCEPROP 0 LASTPIN (5425 3550) $PN 114
J 0
(5435 3560);
DISPLAY 0.680851 (5435 3560);
PAINT MONO (5435 3560);
FORCEPROP 0 LASTPIN (5425 3600) $PN 117
J 0
(5435 3610);
DISPLAY 0.680851 (5435 3610);
PAINT MONO (5435 3610);
FORCEPROP 0 LASTPIN (5425 3650) $PN 119
J 0
(5435 3660);
DISPLAY 0.680851 (5435 3660);
PAINT MONO (5435 3660);
FORCEPROP 0 LASTPIN (5425 3700) $PN 121
J 0
(5435 3710);
DISPLAY 0.680851 (5435 3710);
PAINT MONO (5435 3710);
FORCEPROP 0 LASTPIN (5425 3750) $PN 123
J 0
(5435 3760);
DISPLAY 0.680851 (5435 3760);
PAINT MONO (5435 3760);
FORCEPROP 0 LASTPIN (5425 3800) $PN 125
J 0
(5435 3810);
DISPLAY 0.680851 (5435 3810);
PAINT MONO (5435 3810);
FORCEPROP 0 LASTPIN (5425 3850) $PN 128
J 0
(5435 3860);
DISPLAY 0.680851 (5435 3860);
PAINT MONO (5435 3860);
FORCEPROP 0 LASTPIN (5425 3900) $PN 130
J 0
(5435 3910);
DISPLAY 0.680851 (5435 3910);
PAINT MONO (5435 3910);
FORCEPROP 0 LASTPIN (5425 3950) $PN 132
J 0
(5435 3960);
DISPLAY 0.680851 (5435 3960);
PAINT MONO (5435 3960);
FORCEPROP 0 LASTPIN (5425 4000) $PN 134
J 0
(5435 4010);
DISPLAY 0.680851 (5435 4010);
PAINT MONO (5435 4010);
FORCEPROP 0 LASTPIN (5425 4050) $PN 136
J 0
(5435 4060);
DISPLAY 0.680851 (5435 4060);
PAINT MONO (5435 4060);
FORCEPROP 0 LASTPIN (5425 4100) $PN 139
J 0
(5435 4110);
DISPLAY 0.680851 (5435 4110);
PAINT MONO (5435 4110);
FORCEPROP 0 LASTPIN (5425 4150) $PN 141
J 0
(5435 4160);
DISPLAY 0.680851 (5435 4160);
PAINT MONO (5435 4160);
FORCEPROP 0 LASTPIN (5425 4200) $PN 143
J 0
(5435 4210);
DISPLAY 0.680851 (5435 4210);
PAINT MONO (5435 4210);
FORCEPROP 0 LASTPIN (4225 950) $PN 151
J 2
(4215 960);
DISPLAY 0.680851 (4215 960);
PAINT MONO (4215 960);
FORCEPROP 0 LASTPIN (4225 1000) $PN 153
J 2
(4215 1010);
DISPLAY 0.680851 (4215 1010);
PAINT MONO (4215 1010);
FORCEPROP 0 LASTPIN (4225 1050) $PN 155
J 2
(4215 1060);
DISPLAY 0.680851 (4215 1060);
PAINT MONO (4215 1060);
FORCEPROP 0 LASTPIN (4225 1100) $PN 158
J 2
(4215 1110);
DISPLAY 0.680851 (4215 1110);
PAINT MONO (4215 1110);
FORCEPROP 0 LASTPIN (4225 1150) $PN 160
J 2
(4215 1160);
DISPLAY 0.680851 (4215 1160);
PAINT MONO (4215 1160);
FORCEPROP 0 LASTPIN (4225 1200) $PN 162
J 2
(4215 1210);
DISPLAY 0.680851 (4215 1210);
PAINT MONO (4215 1210);
FORCEPROP 0 LASTPIN (4225 1250) $PN 164
J 2
(4215 1260);
DISPLAY 0.680851 (4215 1260);
PAINT MONO (4215 1260);
FORCEPROP 0 LASTPIN (4225 1300) $PN 166
J 2
(4215 1310);
DISPLAY 0.680851 (4215 1310);
PAINT MONO (4215 1310);
FORCEPROP 0 LASTPIN (4225 1350) $PN 169
J 2
(4215 1360);
DISPLAY 0.680851 (4215 1360);
PAINT MONO (4215 1360);
FORCEPROP 0 LASTPIN (4225 1400) $PN 171
J 2
(4215 1410);
DISPLAY 0.680851 (4215 1410);
PAINT MONO (4215 1410);
FORCEPROP 0 LASTPIN (4225 1450) $PN 173
J 2
(4215 1460);
DISPLAY 0.680851 (4215 1460);
PAINT MONO (4215 1460);
FORCEPROP 0 LASTPIN (4225 1500) $PN 175
J 2
(4215 1510);
DISPLAY 0.680851 (4215 1510);
PAINT MONO (4215 1510);
FORCEPROP 0 LASTPIN (4225 1550) $PN 177
J 2
(4215 1560);
DISPLAY 0.680851 (4215 1560);
PAINT MONO (4215 1560);
FORCEPROP 0 LASTPIN (4225 1600) $PN 180
J 2
(4215 1610);
DISPLAY 0.680851 (4215 1610);
PAINT MONO (4215 1610);
FORCEPROP 0 LASTPIN (4225 1650) $PN 182
J 2
(4215 1660);
DISPLAY 0.680851 (4215 1660);
PAINT MONO (4215 1660);
FORCEPROP 0 LASTPIN (4225 1700) $PN 184
J 2
(4215 1710);
DISPLAY 0.680851 (4215 1710);
PAINT MONO (4215 1710);
FORCEPROP 0 LASTPIN (4225 1750) $PN 186
J 2
(4215 1760);
DISPLAY 0.680851 (4215 1760);
PAINT MONO (4215 1760);
FORCEPROP 0 LASTPIN (4225 1800) $PN 188
J 2
(4215 1810);
DISPLAY 0.680851 (4215 1810);
PAINT MONO (4215 1810);
FORCEPROP 0 LASTPIN (4225 1850) $PN 191
J 2
(4215 1860);
DISPLAY 0.680851 (4215 1860);
PAINT MONO (4215 1860);
FORCEPROP 0 LASTPIN (4225 1900) $PN 193
J 2
(4215 1910);
DISPLAY 0.680851 (4215 1910);
PAINT MONO (4215 1910);
FORCEPROP 0 LASTPIN (4225 1950) $PN 195
J 2
(4215 1960);
DISPLAY 0.680851 (4215 1960);
PAINT MONO (4215 1960);
FORCEPROP 0 LASTPIN (4225 2000) $PN 197
J 2
(4215 2010);
DISPLAY 0.680851 (4215 2010);
PAINT MONO (4215 2010);
FORCEPROP 0 LASTPIN (4225 2050) $PN 199
J 2
(4215 2060);
DISPLAY 0.680851 (4215 2060);
PAINT MONO (4215 2060);
FORCEPROP 0 LASTPIN (4225 2100) $PN 202
J 2
(4215 2110);
DISPLAY 0.680851 (4215 2110);
PAINT MONO (4215 2110);
FORCEPROP 0 LASTPIN (4225 2150) $PN 204
J 2
(4215 2160);
DISPLAY 0.680851 (4215 2160);
PAINT MONO (4215 2160);
FORCEPROP 0 LASTPIN (4225 2200) $PN 206
J 2
(4215 2210);
DISPLAY 0.680851 (4215 2210);
PAINT MONO (4215 2210);
FORCEPROP 0 LASTPIN (4225 2250) $PN 208
J 2
(4215 2260);
DISPLAY 0.680851 (4215 2260);
PAINT MONO (4215 2260);
FORCEPROP 0 LASTPIN (4225 2300) $PN 210
J 2
(4215 2310);
DISPLAY 0.680851 (4215 2310);
PAINT MONO (4215 2310);
FORCEPROP 0 LASTPIN (4225 2350) $PN 212
J 2
(4215 2360);
DISPLAY 0.680851 (4215 2360);
PAINT MONO (4215 2360);
FORCEPROP 0 LASTPIN (4225 2400) $PN 214
J 2
(4215 2410);
DISPLAY 0.680851 (4215 2410);
PAINT MONO (4215 2410);
FORCEPROP 0 LASTPIN (4225 2450) $PN 216
J 2
(4215 2460);
DISPLAY 0.680851 (4215 2460);
PAINT MONO (4215 2460);
FORCEPROP 0 LASTPIN (4225 2500) $PN 219
J 2
(4215 2510);
DISPLAY 0.680851 (4215 2510);
PAINT MONO (4215 2510);
FORCEPROP 0 LASTPIN (4225 2550) $PN 222
J 2
(4215 2560);
DISPLAY 0.680851 (4215 2560);
PAINT MONO (4215 2560);
FORCEPROP 0 LASTPIN (4225 2600) $PN 224
J 2
(4215 2610);
DISPLAY 0.680851 (4215 2610);
PAINT MONO (4215 2610);
FORCEPROP 0 LASTPIN (4225 2650) $PN 226
J 2
(4215 2660);
DISPLAY 0.680851 (4215 2660);
PAINT MONO (4215 2660);
FORCEPROP 0 LASTPIN (4225 2700) $PN 228
J 2
(4215 2710);
DISPLAY 0.680851 (4215 2710);
PAINT MONO (4215 2710);
FORCEPROP 0 LASTPIN (4225 2750) $PN 230
J 2
(4215 2760);
DISPLAY 0.680851 (4215 2760);
PAINT MONO (4215 2760);
FORCEPROP 0 LASTPIN (4225 2800) $PN 233
J 2
(4215 2810);
DISPLAY 0.680851 (4215 2810);
PAINT MONO (4215 2810);
FORCEPROP 0 LASTPIN (4225 2850) $PN 235
J 2
(4215 2860);
DISPLAY 0.680851 (4215 2860);
PAINT MONO (4215 2860);
FORCEPROP 0 LASTPIN (4225 2900) $PN 237
J 2
(4215 2910);
DISPLAY 0.680851 (4215 2910);
PAINT MONO (4215 2910);
FORCEPROP 0 LASTPIN (4225 2950) $PN 240
J 2
(4215 2960);
DISPLAY 0.680851 (4215 2960);
PAINT MONO (4215 2960);
FORCEPROP 0 LASTPIN (4225 3000) $PN 242
J 2
(4215 3010);
DISPLAY 0.680851 (4215 3010);
PAINT MONO (4215 3010);
FORCEPROP 0 LASTPIN (4225 3050) $PN 244
J 2
(4215 3060);
DISPLAY 0.680851 (4215 3060);
PAINT MONO (4215 3060);
FORCEPROP 0 LASTPIN (4225 3100) $PN 246
J 2
(4215 3110);
DISPLAY 0.680851 (4215 3110);
PAINT MONO (4215 3110);
FORCEPROP 0 LASTPIN (4225 3150) $PN 248
J 2
(4215 3160);
DISPLAY 0.680851 (4215 3160);
PAINT MONO (4215 3160);
FORCEPROP 0 LASTPIN (4225 3200) $PN 251
J 2
(4215 3210);
DISPLAY 0.680851 (4215 3210);
PAINT MONO (4215 3210);
FORCEPROP 0 LASTPIN (4225 3250) $PN 253
J 2
(4215 3260);
DISPLAY 0.680851 (4215 3260);
PAINT MONO (4215 3260);
FORCEPROP 0 LASTPIN (4225 3300) $PN 255
J 2
(4215 3310);
DISPLAY 0.680851 (4215 3310);
PAINT MONO (4215 3310);
FORCEPROP 0 LASTPIN (4225 3350) $PN 257
J 2
(4215 3360);
DISPLAY 0.680851 (4215 3360);
PAINT MONO (4215 3360);
FORCEPROP 0 LASTPIN (4225 3400) $PN 259
J 2
(4215 3410);
DISPLAY 0.680851 (4215 3410);
PAINT MONO (4215 3410);
FORCEPROP 0 LASTPIN (4225 3450) $PN 262
J 2
(4215 3460);
DISPLAY 0.680851 (4215 3460);
PAINT MONO (4215 3460);
FORCEPROP 0 LASTPIN (4225 3500) $PN 264
J 2
(4215 3510);
DISPLAY 0.680851 (4215 3510);
PAINT MONO (4215 3510);
FORCEPROP 0 LASTPIN (4225 3550) $PN 266
J 2
(4215 3560);
DISPLAY 0.680851 (4215 3560);
PAINT MONO (4215 3560);
FORCEPROP 0 LASTPIN (4225 3600) $PN 268
J 2
(4215 3610);
DISPLAY 0.680851 (4215 3610);
PAINT MONO (4215 3610);
FORCEPROP 0 LASTPIN (4225 3650) $PN 270
J 2
(4215 3660);
DISPLAY 0.680851 (4215 3660);
PAINT MONO (4215 3660);
FORCEPROP 0 LASTPIN (4225 3700) $PN 273
J 2
(4215 3710);
DISPLAY 0.680851 (4215 3710);
PAINT MONO (4215 3710);
FORCEPROP 0 LASTPIN (4225 3750) $PN 275
J 2
(4215 3760);
DISPLAY 0.680851 (4215 3760);
PAINT MONO (4215 3760);
FORCEPROP 0 LASTPIN (4225 3800) $PN 277
J 2
(4215 3810);
DISPLAY 0.680851 (4215 3810);
PAINT MONO (4215 3810);
FORCEPROP 0 LASTPIN (4225 3850) $PN 279
J 2
(4215 3860);
DISPLAY 0.680851 (4215 3860);
PAINT MONO (4215 3860);
FORCEPROP 0 LASTPIN (4225 3900) $PN 281
J 2
(4215 3910);
DISPLAY 0.680851 (4215 3910);
PAINT MONO (4215 3910);
FORCEPROP 0 LASTPIN (4225 3950) $PN 284
J 2
(4215 3960);
DISPLAY 0.680851 (4215 3960);
PAINT MONO (4215 3960);
FORCEPROP 0 LASTPIN (4225 4000) $PN 286
J 2
(4215 4010);
DISPLAY 0.680851 (4215 4010);
PAINT MONO (4215 4010);
FORCEPROP 0 LASTPIN (4225 4050) $PN 288
J 2
(4215 4060);
DISPLAY 0.680851 (4215 4060);
PAINT MONO (4215 4060);
FORCEPROP 1 LAST NEEDS_NO_SIZE TRUE
J 0
(4825 2575);
DISPLAY 0.723404 (4825 2575);
PAINT GREEN (4825 2575);
DISPLAY INVISIBLE (4825 2575);
FORCEPROP 1 LAST CDS_LMAN_SYM_OUTLINE -450,1775,450,-1775
J 0
(4825 2575);
DISPLAY 0.468085 (4825 2575);
PAINT GREEN (4825 2575);
DISPLAY INVISIBLE (4825 2575);
FORCEPROP 2 LAST CDS_LIB pure_quanta
J 0
(4825 2575);
DISPLAY INVISIBLE (4825 2575);
FORCEPROP 2 LAST CDS_LOCATION J6
J 0
(4375 4700);
DISPLAY 1.021277 (4375 4700);
DISPLAY INVISIBLE (4375 4700);
FORCEPROP 0 LAST $SEC 3
J 0
(4375 4700);
DISPLAY 0.680851 (4375 4700);
PAINT MONO (4375 4700);
DISPLAY INVISIBLE (4375 4700);
FORCEPROP 2 LAST CDS_SEC 3
J 0
(4375 4700);
DISPLAY 1.021277 (4375 4700);
DISPLAY INVISIBLE (4375 4700);
FORCEPROP 1 LAST PATH I175
J 0
(4825 2575);
DISPLAY 0.723404 (4825 2575);
PAINT GREEN (4825 2575);
DISPLAY INVISIBLE (4825 2575);
FORCEADD UNIVERSAL_GND..1
(5675 500);
FORCEPROP 3 LASTPIN (5675 550) SIG_NAME GND\g
J 0
(5685 560);
DISPLAY 0.659574 (5685 560);
PAINT MONO (5685 560);
DISPLAY INVISIBLE (5685 560);
FORCEPROP 2 LAST CDS_LIB logical_power
J 0
(5675 500);
PAINT MONO (5675 500);
DISPLAY INVISIBLE (5675 500);
FORCEPROP 1 LAST HDL_POWER GND
J 1
(5700 425);
DISPLAY 0.872340 (5700 425);
PAINT GREEN (5700 425);
DISPLAY INVISIBLE (5700 425);
FORCEPROP 1 LAST PATH I176
J 0
(5750 500);
DISPLAY 0.872340 (5750 500);
PAINT AQUA (5750 500);
DISPLAY INVISIBLE (5750 500);
FORCEADD OFFPAGE..3
R 2
(-3025 1350);
FORCEPROP 2 LAST $XR0 114 
J 0
(-3305 1350);
DISPLAY 0.638298 (-3305 1350);
PAINT MONO (-3305 1350);
FORCEPROP 2 LAST CDS_LIB standard
J 0
(-3025 1350);
PAINT MONO (-3025 1350);
DISPLAY INVISIBLE (-3025 1350);
FORCEPROP 1 LAST OFFPAGE TRUE
J 2
(-3350 1225);
DISPLAY 0.872340 (-3350 1225);
DISPLAY INVISIBLE (-3350 1225);
FORCEPROP 1 LAST COMMENT_BODY TRUE
J 2
(-2975 1250);
DISPLAY 0.872340 (-2975 1250);
PAINT GREEN (-2975 1250);
DISPLAY INVISIBLE (-2975 1250);
FORCEPROP 2 LAST PATH I177
J 0
(-2975 1425);
DISPLAY 1.021277 (-2975 1425);
DISPLAY INVISIBLE (-2975 1425);
FORCEADD SCONN288_ADR50017P087CC..2
(1400 3200);
FORCEPROP 1 LAST PART_NUMBER DFHST8FS460
J 0
(795 4488);
DISPLAY 0.723404 (795 4488);
PAINT GREEN (795 4488);
DISPLAY INVISIBLE (795 4488);
FORCEPROP 1 LAST MATERIAL IO
J 0
(795 4361);
DISPLAY 0.723404 (795 4361);
PAINT GREEN (795 4361);
FORCEPROP 2 LAST VALUE SCONN288_ADR50017-P087CC
J 0
(800 4675);
DISPLAY 1.021277 (800 4675);
FORCEPROP 2 LAST PART_TYPE SMLF
J 0
(800 4725);
DISPLAY 1.021277 (800 4725);
FORCEPROP 1 LAST LOCATION J6
J 0
(795 4635);
DISPLAY 0.723404 (795 4635);
PAINT GREEN (795 4635);
FORCEPROP 0 LASTPIN (2150 3250) $PN 12
J 0
(2160 3260);
DISPLAY 0.680851 (2160 3260);
PAINT MONO (2160 3260);
FORCEPROP 0 LASTPIN (2150 3300) $PN 11
J 0
(2160 3310);
DISPLAY 0.680851 (2160 3310);
PAINT MONO (2160 3310);
FORCEPROP 0 LASTPIN (2150 2200) $PN 105
J 0
(2160 2210);
DISPLAY 0.680851 (2160 2210);
PAINT MONO (2160 2210);
FORCEPROP 0 LASTPIN (2150 2250) $PN 104
J 0
(2160 2260);
DISPLAY 0.680851 (2160 2260);
PAINT MONO (2160 2260);
FORCEPROP 0 LASTPIN (2150 3350) $PN 23
J 0
(2160 3360);
DISPLAY 0.680851 (2160 3360);
PAINT MONO (2160 3360);
FORCEPROP 0 LASTPIN (2150 3400) $PN 22
J 0
(2160 3410);
DISPLAY 0.680851 (2160 3410);
PAINT MONO (2160 3410);
FORCEPROP 0 LASTPIN (2150 2300) $PN 116
J 0
(2160 2310);
DISPLAY 0.680851 (2160 2310);
PAINT MONO (2160 2310);
FORCEPROP 0 LASTPIN (2150 2350) $PN 115
J 0
(2160 2360);
DISPLAY 0.680851 (2160 2360);
PAINT MONO (2160 2360);
FORCEPROP 0 LASTPIN (2150 3450) $PN 34
J 0
(2160 3460);
DISPLAY 0.680851 (2160 3460);
PAINT MONO (2160 3460);
FORCEPROP 0 LASTPIN (2150 3500) $PN 33
J 0
(2160 3510);
DISPLAY 0.680851 (2160 3510);
PAINT MONO (2160 3510);
FORCEPROP 0 LASTPIN (2150 2400) $PN 127
J 0
(2160 2410);
DISPLAY 0.680851 (2160 2410);
PAINT MONO (2160 2410);
FORCEPROP 0 LASTPIN (2150 2450) $PN 126
J 0
(2160 2460);
DISPLAY 0.680851 (2160 2460);
PAINT MONO (2160 2460);
FORCEPROP 0 LASTPIN (2150 3550) $PN 45
J 0
(2160 3560);
DISPLAY 0.680851 (2160 3560);
PAINT MONO (2160 3560);
FORCEPROP 0 LASTPIN (2150 3600) $PN 44
J 0
(2160 3610);
DISPLAY 0.680851 (2160 3610);
PAINT MONO (2160 3610);
FORCEPROP 0 LASTPIN (2150 2500) $PN 138
J 0
(2160 2510);
DISPLAY 0.680851 (2160 2510);
PAINT MONO (2160 2510);
FORCEPROP 0 LASTPIN (2150 2550) $PN 137
J 0
(2160 2560);
DISPLAY 0.680851 (2160 2560);
PAINT MONO (2160 2560);
FORCEPROP 0 LASTPIN (2150 3650) $PN 56
J 0
(2160 3660);
DISPLAY 0.680851 (2160 3660);
PAINT MONO (2160 3660);
FORCEPROP 0 LASTPIN (2150 3700) $PN 55
J 0
(2160 3710);
DISPLAY 0.680851 (2160 3710);
PAINT MONO (2160 3710);
FORCEPROP 0 LASTPIN (2150 2600) $PN 238
J 0
(2160 2610);
DISPLAY 0.680851 (2160 2610);
PAINT MONO (2160 2610);
FORCEPROP 0 LASTPIN (2150 2650) $PN 239
J 0
(2160 2660);
DISPLAY 0.680851 (2160 2660);
PAINT MONO (2160 2660);
FORCEPROP 0 LASTPIN (2150 3750) $PN 156
J 0
(2160 3760);
DISPLAY 0.680851 (2160 3760);
PAINT MONO (2160 3760);
FORCEPROP 0 LASTPIN (2150 3800) $PN 157
J 0
(2160 3810);
DISPLAY 0.680851 (2160 3810);
PAINT MONO (2160 3810);
FORCEPROP 0 LASTPIN (2150 2700) $PN 249
J 0
(2160 2710);
DISPLAY 0.680851 (2160 2710);
PAINT MONO (2160 2710);
FORCEPROP 0 LASTPIN (2150 2750) $PN 250
J 0
(2160 2760);
DISPLAY 0.680851 (2160 2760);
PAINT MONO (2160 2760);
FORCEPROP 0 LASTPIN (2150 3850) $PN 167
J 0
(2160 3860);
DISPLAY 0.680851 (2160 3860);
PAINT MONO (2160 3860);
FORCEPROP 0 LASTPIN (2150 3900) $PN 168
J 0
(2160 3910);
DISPLAY 0.680851 (2160 3910);
PAINT MONO (2160 3910);
FORCEPROP 0 LASTPIN (2150 2800) $PN 260
J 0
(2160 2810);
DISPLAY 0.680851 (2160 2810);
PAINT MONO (2160 2810);
FORCEPROP 0 LASTPIN (2150 2850) $PN 261
J 0
(2160 2860);
DISPLAY 0.680851 (2160 2860);
PAINT MONO (2160 2860);
FORCEPROP 0 LASTPIN (2150 3950) $PN 178
J 0
(2160 3960);
DISPLAY 0.680851 (2160 3960);
PAINT MONO (2160 3960);
FORCEPROP 0 LASTPIN (2150 4000) $PN 179
J 0
(2160 4010);
DISPLAY 0.680851 (2160 4010);
PAINT MONO (2160 4010);
FORCEPROP 0 LASTPIN (2150 2900) $PN 271
J 0
(2160 2910);
DISPLAY 0.680851 (2160 2910);
PAINT MONO (2160 2910);
FORCEPROP 0 LASTPIN (2150 2950) $PN 272
J 0
(2160 2960);
DISPLAY 0.680851 (2160 2960);
PAINT MONO (2160 2960);
FORCEPROP 0 LASTPIN (2150 4050) $PN 189
J 0
(2160 4060);
DISPLAY 0.680851 (2160 4060);
PAINT MONO (2160 4060);
FORCEPROP 0 LASTPIN (2150 4100) $PN 190
J 0
(2160 4110);
DISPLAY 0.680851 (2160 4110);
PAINT MONO (2160 4110);
FORCEPROP 0 LASTPIN (2150 3000) $PN 282
J 0
(2160 3010);
DISPLAY 0.680851 (2160 3010);
PAINT MONO (2160 3010);
FORCEPROP 0 LASTPIN (2150 3050) $PN 283
J 0
(2160 3060);
DISPLAY 0.680851 (2160 3060);
PAINT MONO (2160 3060);
FORCEPROP 0 LASTPIN (2150 4150) $PN 200
J 0
(2160 4160);
DISPLAY 0.680851 (2160 4160);
PAINT MONO (2160 4160);
FORCEPROP 0 LASTPIN (2150 4200) $PN 201
J 0
(2160 4210);
DISPLAY 0.680851 (2160 4210);
PAINT MONO (2160 4210);
FORCEPROP 0 LASTPIN (2150 3100) $PN 94
J 0
(2160 3110);
DISPLAY 0.680851 (2160 3110);
PAINT MONO (2160 3110);
FORCEPROP 0 LASTPIN (2150 3150) $PN 93
J 0
(2160 3160);
DISPLAY 0.680851 (2160 3160);
PAINT MONO (2160 3160);
FORCEPROP 1 LAST NEEDS_NO_SIZE TRUE
J 0
(1400 3200);
DISPLAY 0.723404 (1400 3200);
PAINT GREEN (1400 3200);
DISPLAY INVISIBLE (1400 3200);
FORCEPROP 1 LAST CDS_LMAN_SYM_OUTLINE -600,1150,600,-1150
J 0
(1400 3200);
DISPLAY 0.468085 (1400 3200);
PAINT GREEN (1400 3200);
DISPLAY INVISIBLE (1400 3200);
FORCEPROP 2 LAST CDS_LIB pure_quanta
J 0
(1400 3200);
DISPLAY INVISIBLE (1400 3200);
FORCEPROP 0 LAST $SEC 2
J 0
(800 4775);
DISPLAY 0.680851 (800 4775);
PAINT MONO (800 4775);
DISPLAY INVISIBLE (800 4775);
FORCEPROP 0 LAST CDS_SEC 2
J 0
(800 4775);
DISPLAY 1.021277 (800 4775);
DISPLAY INVISIBLE (800 4775);
FORCEPROP 1 LAST PATH I178
J 0
(1400 3200);
DISPLAY 0.723404 (1400 3200);
PAINT GREEN (1400 3200);
DISPLAY INVISIBLE (1400 3200);
FORCEADD OFFPAGE..1
(-1925 1450);
FORCEPROP 2 LAST $XR7 89 
J 0
(-2837 1450);
DISPLAY 0.638298 (-2837 1450);
PAINT MONO (-2837 1450);
FORCEPROP 2 LAST $XR6 88 
J 0
(-2747 1450);
DISPLAY 0.638298 (-2747 1450);
PAINT MONO (-2747 1450);
FORCEPROP 2 LAST $XR5 86 
J 0
(-2657 1450);
DISPLAY 0.638298 (-2657 1450);
PAINT MONO (-2657 1450);
FORCEPROP 2 LAST $XR4 85 
J 0
(-2567 1450);
DISPLAY 0.638298 (-2567 1450);
PAINT MONO (-2567 1450);
FORCEPROP 2 LAST $XR3 84 
J 0
(-2477 1450);
DISPLAY 0.638298 (-2477 1450);
PAINT MONO (-2477 1450);
FORCEPROP 2 LAST $XR2 83 
J 0
(-2387 1450);
DISPLAY 0.638298 (-2387 1450);
PAINT MONO (-2387 1450);
FORCEPROP 2 LAST $XR1 82 
J 0
(-2297 1450);
DISPLAY 0.638298 (-2297 1450);
PAINT MONO (-2297 1450);
FORCEPROP 2 LAST $XR0 229 
J 0
(-2207 1450);
DISPLAY 0.638298 (-2207 1450);
PAINT MONO (-2207 1450);
FORCEPROP 2 LAST CDS_LIB standard
J 0
(-1925 1450);
PAINT MONO (-1925 1450);
DISPLAY INVISIBLE (-1925 1450);
FORCEPROP 1 LAST OFFPAGE TRUE
J 0
(-1600 1325);
DISPLAY 0.872340 (-1600 1325);
DISPLAY INVISIBLE (-1600 1325);
FORCEPROP 1 LAST COMMENT_BODY TRUE
J 0
(-1800 1350);
DISPLAY 0.872340 (-1800 1350);
PAINT GREEN (-1800 1350);
DISPLAY INVISIBLE (-1800 1350);
FORCEPROP 2 LAST PATH I179
J 2
(-2375 1500);
DISPLAY 1.021277 (-2375 1500);
DISPLAY INVISIBLE (-2375 1500);
FORCEADD OFFPAGE..1
(-3025 3400);
FORCEPROP 2 LAST $XR1 86 
J 0
(-3336 3400);
DISPLAY 0.638298 (-3336 3400);
PAINT MONO (-3336 3400);
FORCEPROP 2 LAST $XR0 22 
J 0
(-3246 3400);
DISPLAY 0.638298 (-3246 3400);
PAINT MONO (-3246 3400);
FORCEPROP 2 LAST CDS_LIB standard
J 0
(-3025 3400);
PAINT MONO (-3025 3400);
DISPLAY INVISIBLE (-3025 3400);
FORCEPROP 1 LAST OFFPAGE TRUE
J 0
(-2700 3275);
DISPLAY 0.872340 (-2700 3275);
DISPLAY INVISIBLE (-2700 3275);
FORCEPROP 1 LAST COMMENT_BODY TRUE
J 0
(-2900 3300);
DISPLAY 0.872340 (-2900 3300);
PAINT GREEN (-2900 3300);
DISPLAY INVISIBLE (-2900 3300);
FORCEPROP 2 LAST PATH I18
J 0
(-2975 3475);
DISPLAY 1.021277 (-2975 3475);
DISPLAY INVISIBLE (-2975 3475);
FORCEADD Q_RES..1
(-3150 1500);
FORCEPROP 1 LAST PART_NUMBER CS04992FB07
J 0
(-3050 1475);
DISPLAY 0.404255 (-3050 1475);
DISPLAY INVISIBLE (-3050 1475);
FORCEPROP 1 LAST MATERIAL CHIP
J 0
(-3050 1450);
DISPLAY 0.404255 (-3050 1450);
FORCEPROP 1 LAST VALUE 49.9
J 2
(-2950 1500);
DISPLAY 0.510638 (-2950 1500);
FORCEPROP 1 LAST $LOCATION R3880
J 0
(-3400 1500);
DISPLAY 0.638298 (-3400 1500);
FORCEPROP 1 LASTPIN (-3250 1500) $PN 1
J 0
(-3238 1512);
DISPLAY 0.787234 (-3238 1512);
PAINT MONO (-3238 1512);
FORCEPROP 1 LASTPIN (-3050 1500) $PN 2
J 0
(-3088 1512);
DISPLAY 0.787234 (-3088 1512);
PAINT MONO (-3088 1512);
FORCEPROP 2 LAST CDS_LIB pure_quanta
J 0
(-3150 1500);
DISPLAY INVISIBLE (-3150 1500);
FORCEPROP 1 LAST PACK_TYPE 0402LF
J 0
(-2850 1500);
DISPLAY 0.510638 (-2850 1500);
DISPLAY INVISIBLE (-2850 1500);
FORCEPROP 1 LAST TOLERANCE 1%
J 0
(-2925 1500);
DISPLAY 0.510638 (-2925 1500);
DISPLAY INVISIBLE (-2925 1500);
FORCEPROP 1 LAST WATTAGE 1/16W
J 2
(-2850 1450);
DISPLAY 0.404255 (-2850 1450);
DISPLAY INVISIBLE (-2850 1450);
FORCEPROP 0 LAST CDS_LOCATION R3880
J 0
(-3275 1550);
DISPLAY 1.021277 (-3275 1550);
DISPLAY INVISIBLE (-3275 1550);
FORCEPROP 0 LAST $SEC 1
J 0
(-3275 1550);
DISPLAY 0.680851 (-3275 1550);
PAINT MONO (-3275 1550);
DISPLAY INVISIBLE (-3275 1550);
FORCEPROP 0 LAST CDS_SEC 1
J 0
(-3275 1550);
DISPLAY 1.021277 (-3275 1550);
DISPLAY INVISIBLE (-3275 1550);
FORCEPROP 1 LAST PATH I180
J 0
(-3200 1650);
DISPLAY 0.978723 (-3200 1650);
PAINT WHITE (-3200 1650);
DISPLAY INVISIBLE (-3200 1650);
FORCEADD OFFPAGE..1
(-3025 3825);
FORCEPROP 2 LAST $XR1 86 
J 0
(-3336 3825);
DISPLAY 0.638298 (-3336 3825);
PAINT MONO (-3336 3825);
FORCEPROP 2 LAST $XR0 22 
J 0
(-3246 3825);
DISPLAY 0.638298 (-3246 3825);
PAINT MONO (-3246 3825);
FORCEPROP 2 LAST CDS_LIB standard
J 0
(-3025 3825);
PAINT MONO (-3025 3825);
DISPLAY INVISIBLE (-3025 3825);
FORCEPROP 1 LAST OFFPAGE TRUE
J 0
(-2700 3700);
DISPLAY 0.872340 (-2700 3700);
DISPLAY INVISIBLE (-2700 3700);
FORCEPROP 1 LAST COMMENT_BODY TRUE
J 0
(-2900 3725);
DISPLAY 0.872340 (-2900 3725);
PAINT GREEN (-2900 3725);
DISPLAY INVISIBLE (-2900 3725);
FORCEPROP 2 LAST PATH I19
J 0
(-2975 3900);
DISPLAY 1.021277 (-2975 3900);
DISPLAY INVISIBLE (-2975 3900);
FORCEADD OFFPAGE..2
R 2
(-3025 750);
FORCEPROP 2 LAST $XR0 22 
J 0
(-3249 750);
DISPLAY 0.638298 (-3249 750);
PAINT MONO (-3249 750);
FORCEPROP 2 LAST CDS_LIB standard
J 0
(-3025 750);
PAINT MONO (-3025 750);
DISPLAY INVISIBLE (-3025 750);
FORCEPROP 1 LAST OFFPAGE TRUE
J 2
(-3350 625);
DISPLAY 0.872340 (-3350 625);
DISPLAY INVISIBLE (-3350 625);
FORCEPROP 1 LAST COMMENT_BODY TRUE
J 2
(-2980 655);
DISPLAY 0.872340 (-2980 655);
PAINT GREEN (-2980 655);
DISPLAY INVISIBLE (-2980 655);
FORCEPROP 2 LAST PATH I2
J 0
(-2975 825);
DISPLAY 1.021277 (-2975 825);
DISPLAY INVISIBLE (-2975 825);
FORCEADD VCC_CORE..1
(-2925 2075);
FORCEPROP 3 LASTPIN (-2925 2025) SIG_NAME P3V3_AUX\g
J 0
(-2915 2035);
DISPLAY 0.659574 (-2915 2035);
PAINT MONO (-2915 2035);
DISPLAY INVISIBLE (-2915 2035);
FORCEPROP 1 LAST HDL_POWER P3V3_AUX
J 1
(-2925 2125);
DISPLAY 1.148936 (-2925 2125);
PAINT GREEN (-2925 2125);
FORCEPROP 2 LAST CDS_LIB logical_power
J 0
(-2925 2075);
PAINT MONO (-2925 2075);
DISPLAY INVISIBLE (-2925 2075);
FORCEPROP 1 LAST PATH I20
J 0
(-2875 2100);
DISPLAY 0.872340 (-2875 2100);
PAINT AQUA (-2875 2100);
DISPLAY INVISIBLE (-2875 2100);
FORCEADD TAP..1
R 2
(-2100 2050);
FORCEPROP 3 LASTPIN (-2050 2050) SIG_NAME M_C_CPU0_SB_CB<1>
J 0
(-2040 2060);
DISPLAY 0.659574 (-2040 2060);
PAINT MONO (-2040 2060);
DISPLAY INVISIBLE (-2040 2060);
FORCEPROP 1 LASTPIN (-2050 2050) BN 1
J 2
(-2038 2058);
DISPLAY 0.680851 (-2038 2058);
PAINT GREEN (-2038 2058);
FORCEPROP 2 LAST CDS_LIB standard
J 0
(-2100 2050);
DISPLAY INVISIBLE (-2100 2050);
FORCEPROP 1 LAST BODY_TYPE PLUMBING
J 2
(-2100 2100);
DISPLAY 0.872340 (-2100 2100);
PAINT GREEN (-2100 2100);
DISPLAY INVISIBLE (-2100 2100);
FORCEPROP 1 LAST HDL_TAP TRUE
J 2
(-2425 1925);
DISPLAY 0.872340 (-2425 1925);
DISPLAY INVISIBLE (-2425 1925);
FORCEPROP 1 LAST PATH I21
J 2
(-2098 2050);
DISPLAY 0.872340 (-2098 2050);
PAINT GREEN (-2098 2050);
DISPLAY INVISIBLE (-2098 2050);
FORCEADD TAP..1
R 2
(-2100 2000);
FORCEPROP 3 LASTPIN (-2050 2000) SIG_NAME M_C_CPU0_SB_CB<0>
J 0
(-2040 2010);
DISPLAY 0.659574 (-2040 2010);
PAINT MONO (-2040 2010);
DISPLAY INVISIBLE (-2040 2010);
FORCEPROP 1 LASTPIN (-2050 2000) BN 0
J 2
(-2038 2008);
DISPLAY 0.680851 (-2038 2008);
PAINT GREEN (-2038 2008);
FORCEPROP 2 LAST CDS_LIB standard
J 0
(-2100 2000);
PAINT MONO (-2100 2000);
DISPLAY INVISIBLE (-2100 2000);
FORCEPROP 1 LAST BODY_TYPE PLUMBING
J 2
(-2100 2050);
DISPLAY 0.872340 (-2100 2050);
PAINT GREEN (-2100 2050);
DISPLAY INVISIBLE (-2100 2050);
FORCEPROP 1 LAST HDL_TAP TRUE
J 2
(-2425 1875);
DISPLAY 0.872340 (-2425 1875);
DISPLAY INVISIBLE (-2425 1875);
FORCEPROP 1 LAST PATH I22
J 2
(-2098 2000);
DISPLAY 0.872340 (-2098 2000);
PAINT GREEN (-2098 2000);
DISPLAY INVISIBLE (-2098 2000);
FORCEADD TAP..1
R 2
(-2100 2100);
FORCEPROP 3 LASTPIN (-2050 2100) SIG_NAME M_C_CPU0_SB_CB<2>
J 0
(-2040 2110);
DISPLAY 0.659574 (-2040 2110);
PAINT MONO (-2040 2110);
DISPLAY INVISIBLE (-2040 2110);
FORCEPROP 1 LASTPIN (-2050 2100) BN 2
J 2
(-2038 2108);
DISPLAY 0.680851 (-2038 2108);
PAINT GREEN (-2038 2108);
FORCEPROP 2 LAST CDS_LIB standard
J 0
(-2100 2100);
DISPLAY INVISIBLE (-2100 2100);
FORCEPROP 1 LAST BODY_TYPE PLUMBING
J 2
(-2100 2150);
DISPLAY 0.872340 (-2100 2150);
PAINT GREEN (-2100 2150);
DISPLAY INVISIBLE (-2100 2150);
FORCEPROP 1 LAST HDL_TAP TRUE
J 2
(-2425 1975);
DISPLAY 0.872340 (-2425 1975);
DISPLAY INVISIBLE (-2425 1975);
FORCEPROP 1 LAST PATH I23
J 2
(-2098 2100);
DISPLAY 0.872340 (-2098 2100);
PAINT GREEN (-2098 2100);
DISPLAY INVISIBLE (-2098 2100);
FORCEADD TAP..1
R 2
(-2100 2200);
FORCEPROP 3 LASTPIN (-2050 2200) SIG_NAME M_C_CPU0_SB_CB<4>
J 0
(-2040 2210);
DISPLAY 0.659574 (-2040 2210);
PAINT MONO (-2040 2210);
DISPLAY INVISIBLE (-2040 2210);
FORCEPROP 1 LASTPIN (-2050 2200) BN 4
J 2
(-2038 2208);
DISPLAY 0.680851 (-2038 2208);
PAINT GREEN (-2038 2208);
FORCEPROP 2 LAST CDS_LIB standard
J 0
(-2100 2200);
DISPLAY INVISIBLE (-2100 2200);
FORCEPROP 1 LAST BODY_TYPE PLUMBING
J 2
(-2100 2250);
DISPLAY 0.872340 (-2100 2250);
PAINT GREEN (-2100 2250);
DISPLAY INVISIBLE (-2100 2250);
FORCEPROP 1 LAST HDL_TAP TRUE
J 2
(-2425 2075);
DISPLAY 0.872340 (-2425 2075);
DISPLAY INVISIBLE (-2425 2075);
FORCEPROP 1 LAST PATH I24
J 2
(-2098 2200);
DISPLAY 0.872340 (-2098 2200);
PAINT GREEN (-2098 2200);
DISPLAY INVISIBLE (-2098 2200);
FORCEADD TAP..1
R 2
(-2100 2150);
FORCEPROP 3 LASTPIN (-2050 2150) SIG_NAME M_C_CPU0_SB_CB<3>
J 0
(-2040 2160);
DISPLAY 0.659574 (-2040 2160);
PAINT MONO (-2040 2160);
DISPLAY INVISIBLE (-2040 2160);
FORCEPROP 1 LASTPIN (-2050 2150) BN 3
J 2
(-2038 2158);
DISPLAY 0.680851 (-2038 2158);
PAINT GREEN (-2038 2158);
FORCEPROP 2 LAST CDS_LIB standard
J 0
(-2100 2150);
DISPLAY INVISIBLE (-2100 2150);
FORCEPROP 1 LAST BODY_TYPE PLUMBING
J 2
(-2100 2200);
DISPLAY 0.872340 (-2100 2200);
PAINT GREEN (-2100 2200);
DISPLAY INVISIBLE (-2100 2200);
FORCEPROP 1 LAST HDL_TAP TRUE
J 2
(-2425 2025);
DISPLAY 0.872340 (-2425 2025);
DISPLAY INVISIBLE (-2425 2025);
FORCEPROP 1 LAST PATH I25
J 2
(-2098 2150);
DISPLAY 0.872340 (-2098 2150);
PAINT GREEN (-2098 2150);
DISPLAY INVISIBLE (-2098 2150);
FORCEADD TAP..1
R 2
(-2100 2300);
FORCEPROP 3 LASTPIN (-2050 2300) SIG_NAME M_C_CPU0_SB_CB<6>
J 0
(-2040 2310);
DISPLAY 0.659574 (-2040 2310);
PAINT MONO (-2040 2310);
DISPLAY INVISIBLE (-2040 2310);
FORCEPROP 1 LASTPIN (-2050 2300) BN 6
J 2
(-2038 2308);
DISPLAY 0.680851 (-2038 2308);
PAINT GREEN (-2038 2308);
FORCEPROP 2 LAST CDS_LIB standard
J 0
(-2100 2300);
DISPLAY INVISIBLE (-2100 2300);
FORCEPROP 1 LAST BODY_TYPE PLUMBING
J 2
(-2100 2350);
DISPLAY 0.872340 (-2100 2350);
PAINT GREEN (-2100 2350);
DISPLAY INVISIBLE (-2100 2350);
FORCEPROP 1 LAST HDL_TAP TRUE
J 2
(-2425 2175);
DISPLAY 0.872340 (-2425 2175);
DISPLAY INVISIBLE (-2425 2175);
FORCEPROP 1 LAST PATH I26
J 2
(-2098 2300);
DISPLAY 0.872340 (-2098 2300);
PAINT GREEN (-2098 2300);
DISPLAY INVISIBLE (-2098 2300);
FORCEADD TAP..1
R 2
(-2100 2250);
FORCEPROP 3 LASTPIN (-2050 2250) SIG_NAME M_C_CPU0_SB_CB<5>
J 0
(-2040 2260);
DISPLAY 0.659574 (-2040 2260);
PAINT MONO (-2040 2260);
DISPLAY INVISIBLE (-2040 2260);
FORCEPROP 1 LASTPIN (-2050 2250) BN 5
J 2
(-2038 2258);
DISPLAY 0.680851 (-2038 2258);
PAINT GREEN (-2038 2258);
FORCEPROP 2 LAST CDS_LIB standard
J 0
(-2100 2250);
DISPLAY INVISIBLE (-2100 2250);
FORCEPROP 1 LAST BODY_TYPE PLUMBING
J 2
(-2100 2300);
DISPLAY 0.872340 (-2100 2300);
PAINT GREEN (-2100 2300);
DISPLAY INVISIBLE (-2100 2300);
FORCEPROP 1 LAST HDL_TAP TRUE
J 2
(-2425 2125);
DISPLAY 0.872340 (-2425 2125);
DISPLAY INVISIBLE (-2425 2125);
FORCEPROP 1 LAST PATH I27
J 2
(-2098 2250);
DISPLAY 0.872340 (-2098 2250);
PAINT GREEN (-2098 2250);
DISPLAY INVISIBLE (-2098 2250);
FORCEADD TAP..1
R 2
(-2100 2350);
FORCEPROP 3 LASTPIN (-2050 2350) SIG_NAME M_C_CPU0_SB_CB<7>
J 0
(-2040 2360);
DISPLAY 0.659574 (-2040 2360);
PAINT MONO (-2040 2360);
DISPLAY INVISIBLE (-2040 2360);
FORCEPROP 1 LASTPIN (-2050 2350) BN 7
J 2
(-2038 2358);
DISPLAY 0.680851 (-2038 2358);
PAINT GREEN (-2038 2358);
FORCEPROP 2 LAST CDS_LIB standard
J 0
(-2100 2350);
DISPLAY INVISIBLE (-2100 2350);
FORCEPROP 1 LAST BODY_TYPE PLUMBING
J 2
(-2100 2400);
DISPLAY 0.872340 (-2100 2400);
PAINT GREEN (-2100 2400);
DISPLAY INVISIBLE (-2100 2400);
FORCEPROP 1 LAST HDL_TAP TRUE
J 2
(-2425 2225);
DISPLAY 0.872340 (-2425 2225);
DISPLAY INVISIBLE (-2425 2225);
FORCEPROP 1 LAST PATH I28
J 2
(-2098 2350);
DISPLAY 0.872340 (-2098 2350);
PAINT GREEN (-2098 2350);
DISPLAY INVISIBLE (-2098 2350);
FORCEADD TAP..1
R 2
(-2100 2550);
FORCEPROP 3 LASTPIN (-2050 2550) SIG_NAME M_C_CPU0_SA_CB<2>
J 0
(-2040 2560);
DISPLAY 0.659574 (-2040 2560);
PAINT MONO (-2040 2560);
DISPLAY INVISIBLE (-2040 2560);
FORCEPROP 1 LASTPIN (-2050 2550) BN 2
J 2
(-2038 2558);
DISPLAY 0.680851 (-2038 2558);
PAINT GREEN (-2038 2558);
FORCEPROP 2 LAST CDS_LIB standard
J 0
(-2100 2550);
DISPLAY INVISIBLE (-2100 2550);
FORCEPROP 1 LAST BODY_TYPE PLUMBING
J 2
(-2100 2600);
DISPLAY 0.872340 (-2100 2600);
PAINT GREEN (-2100 2600);
DISPLAY INVISIBLE (-2100 2600);
FORCEPROP 1 LAST HDL_TAP TRUE
J 2
(-2425 2425);
DISPLAY 0.872340 (-2425 2425);
DISPLAY INVISIBLE (-2425 2425);
FORCEPROP 1 LAST PATH I29
J 2
(-2098 2550);
DISPLAY 0.872340 (-2098 2550);
PAINT GREEN (-2098 2550);
DISPLAY INVISIBLE (-2098 2550);
FORCEADD OFFPAGE..2
R 2
(-3025 800);
FORCEPROP 2 LAST $XR0 22 
J 0
(-3249 800);
DISPLAY 0.638298 (-3249 800);
PAINT MONO (-3249 800);
FORCEPROP 2 LAST CDS_LIB standard
J 0
(-3025 800);
PAINT MONO (-3025 800);
DISPLAY INVISIBLE (-3025 800);
FORCEPROP 1 LAST OFFPAGE TRUE
J 2
(-3350 675);
DISPLAY 0.872340 (-3350 675);
DISPLAY INVISIBLE (-3350 675);
FORCEPROP 1 LAST COMMENT_BODY TRUE
J 2
(-2980 705);
DISPLAY 0.872340 (-2980 705);
PAINT GREEN (-2980 705);
DISPLAY INVISIBLE (-2980 705);
FORCEPROP 2 LAST PATH I3
J 0
(-2975 875);
DISPLAY 1.021277 (-2975 875);
DISPLAY INVISIBLE (-2975 875);
FORCEADD TAP..1
R 2
(-2100 2450);
FORCEPROP 3 LASTPIN (-2050 2450) SIG_NAME M_C_CPU0_SA_CB<0>
J 0
(-2040 2460);
DISPLAY 0.659574 (-2040 2460);
PAINT MONO (-2040 2460);
DISPLAY INVISIBLE (-2040 2460);
FORCEPROP 1 LASTPIN (-2050 2450) BN 0
J 2
(-2038 2458);
DISPLAY 0.680851 (-2038 2458);
PAINT GREEN (-2038 2458);
FORCEPROP 2 LAST CDS_LIB standard
J 0
(-2100 2450);
PAINT MONO (-2100 2450);
DISPLAY INVISIBLE (-2100 2450);
FORCEPROP 1 LAST BODY_TYPE PLUMBING
J 2
(-2100 2500);
DISPLAY 0.872340 (-2100 2500);
PAINT GREEN (-2100 2500);
DISPLAY INVISIBLE (-2100 2500);
FORCEPROP 1 LAST HDL_TAP TRUE
J 2
(-2425 2325);
DISPLAY 0.872340 (-2425 2325);
DISPLAY INVISIBLE (-2425 2325);
FORCEPROP 1 LAST PATH I30
J 2
(-2098 2450);
DISPLAY 0.872340 (-2098 2450);
PAINT GREEN (-2098 2450);
DISPLAY INVISIBLE (-2098 2450);
FORCEADD TAP..1
R 2
(-2100 2500);
FORCEPROP 3 LASTPIN (-2050 2500) SIG_NAME M_C_CPU0_SA_CB<1>
J 0
(-2040 2510);
DISPLAY 0.659574 (-2040 2510);
PAINT MONO (-2040 2510);
DISPLAY INVISIBLE (-2040 2510);
FORCEPROP 1 LASTPIN (-2050 2500) BN 1
J 2
(-2038 2508);
DISPLAY 0.680851 (-2038 2508);
PAINT GREEN (-2038 2508);
FORCEPROP 2 LAST CDS_LIB standard
J 0
(-2100 2500);
DISPLAY INVISIBLE (-2100 2500);
FORCEPROP 1 LAST BODY_TYPE PLUMBING
J 2
(-2100 2550);
DISPLAY 0.872340 (-2100 2550);
PAINT GREEN (-2100 2550);
DISPLAY INVISIBLE (-2100 2550);
FORCEPROP 1 LAST HDL_TAP TRUE
J 2
(-2425 2375);
DISPLAY 0.872340 (-2425 2375);
DISPLAY INVISIBLE (-2425 2375);
FORCEPROP 1 LAST PATH I31
J 2
(-2098 2500);
DISPLAY 0.872340 (-2098 2500);
PAINT GREEN (-2098 2500);
DISPLAY INVISIBLE (-2098 2500);
FORCEADD TAP..1
R 2
(-2100 2600);
FORCEPROP 3 LASTPIN (-2050 2600) SIG_NAME M_C_CPU0_SA_CB<3>
J 0
(-2040 2610);
DISPLAY 0.659574 (-2040 2610);
PAINT MONO (-2040 2610);
DISPLAY INVISIBLE (-2040 2610);
FORCEPROP 1 LASTPIN (-2050 2600) BN 3
J 2
(-2038 2608);
DISPLAY 0.680851 (-2038 2608);
PAINT GREEN (-2038 2608);
FORCEPROP 2 LAST CDS_LIB standard
J 0
(-2100 2600);
DISPLAY INVISIBLE (-2100 2600);
FORCEPROP 1 LAST BODY_TYPE PLUMBING
J 2
(-2100 2650);
DISPLAY 0.872340 (-2100 2650);
PAINT GREEN (-2100 2650);
DISPLAY INVISIBLE (-2100 2650);
FORCEPROP 1 LAST HDL_TAP TRUE
J 2
(-2425 2475);
DISPLAY 0.872340 (-2425 2475);
DISPLAY INVISIBLE (-2425 2475);
FORCEPROP 1 LAST PATH I32
J 2
(-2098 2600);
DISPLAY 0.872340 (-2098 2600);
PAINT GREEN (-2098 2600);
DISPLAY INVISIBLE (-2098 2600);
FORCEADD TAP..1
R 2
(-2100 2700);
FORCEPROP 3 LASTPIN (-2050 2700) SIG_NAME M_C_CPU0_SA_CB<5>
J 0
(-2040 2710);
DISPLAY 0.659574 (-2040 2710);
PAINT MONO (-2040 2710);
DISPLAY INVISIBLE (-2040 2710);
FORCEPROP 1 LASTPIN (-2050 2700) BN 5
J 2
(-2038 2708);
DISPLAY 0.680851 (-2038 2708);
PAINT GREEN (-2038 2708);
FORCEPROP 2 LAST CDS_LIB standard
J 0
(-2100 2700);
DISPLAY INVISIBLE (-2100 2700);
FORCEPROP 1 LAST BODY_TYPE PLUMBING
J 2
(-2100 2750);
DISPLAY 0.872340 (-2100 2750);
PAINT GREEN (-2100 2750);
DISPLAY INVISIBLE (-2100 2750);
FORCEPROP 1 LAST HDL_TAP TRUE
J 2
(-2425 2575);
DISPLAY 0.872340 (-2425 2575);
DISPLAY INVISIBLE (-2425 2575);
FORCEPROP 1 LAST PATH I33
J 2
(-2098 2700);
DISPLAY 0.872340 (-2098 2700);
PAINT GREEN (-2098 2700);
DISPLAY INVISIBLE (-2098 2700);
FORCEADD TAP..1
R 2
(-2100 2650);
FORCEPROP 3 LASTPIN (-2050 2650) SIG_NAME M_C_CPU0_SA_CB<4>
J 0
(-2040 2660);
DISPLAY 0.659574 (-2040 2660);
PAINT MONO (-2040 2660);
DISPLAY INVISIBLE (-2040 2660);
FORCEPROP 1 LASTPIN (-2050 2650) BN 4
J 2
(-2038 2658);
DISPLAY 0.680851 (-2038 2658);
PAINT GREEN (-2038 2658);
FORCEPROP 2 LAST CDS_LIB standard
J 0
(-2100 2650);
DISPLAY INVISIBLE (-2100 2650);
FORCEPROP 1 LAST BODY_TYPE PLUMBING
J 2
(-2100 2700);
DISPLAY 0.872340 (-2100 2700);
PAINT GREEN (-2100 2700);
DISPLAY INVISIBLE (-2100 2700);
FORCEPROP 1 LAST HDL_TAP TRUE
J 2
(-2425 2525);
DISPLAY 0.872340 (-2425 2525);
DISPLAY INVISIBLE (-2425 2525);
FORCEPROP 1 LAST PATH I34
J 2
(-2098 2650);
DISPLAY 0.872340 (-2098 2650);
PAINT GREEN (-2098 2650);
DISPLAY INVISIBLE (-2098 2650);
FORCEADD TAP..1
R 2
(-2100 2800);
FORCEPROP 3 LASTPIN (-2050 2800) SIG_NAME M_C_CPU0_SA_CB<7>
J 0
(-2040 2810);
DISPLAY 0.659574 (-2040 2810);
PAINT MONO (-2040 2810);
DISPLAY INVISIBLE (-2040 2810);
FORCEPROP 1 LASTPIN (-2050 2800) BN 7
J 2
(-2038 2808);
DISPLAY 0.680851 (-2038 2808);
PAINT GREEN (-2038 2808);
FORCEPROP 2 LAST CDS_LIB standard
J 0
(-2100 2800);
DISPLAY INVISIBLE (-2100 2800);
FORCEPROP 1 LAST BODY_TYPE PLUMBING
J 2
(-2100 2850);
DISPLAY 0.872340 (-2100 2850);
PAINT GREEN (-2100 2850);
DISPLAY INVISIBLE (-2100 2850);
FORCEPROP 1 LAST HDL_TAP TRUE
J 2
(-2425 2675);
DISPLAY 0.872340 (-2425 2675);
DISPLAY INVISIBLE (-2425 2675);
FORCEPROP 1 LAST PATH I35
J 2
(-2098 2800);
DISPLAY 0.872340 (-2098 2800);
PAINT GREEN (-2098 2800);
DISPLAY INVISIBLE (-2098 2800);
FORCEADD TAP..1
R 2
(-2100 2750);
FORCEPROP 3 LASTPIN (-2050 2750) SIG_NAME M_C_CPU0_SA_CB<6>
J 0
(-2040 2760);
DISPLAY 0.659574 (-2040 2760);
PAINT MONO (-2040 2760);
DISPLAY INVISIBLE (-2040 2760);
FORCEPROP 1 LASTPIN (-2050 2750) BN 6
J 2
(-2038 2758);
DISPLAY 0.680851 (-2038 2758);
PAINT GREEN (-2038 2758);
FORCEPROP 2 LAST CDS_LIB standard
J 0
(-2100 2750);
DISPLAY INVISIBLE (-2100 2750);
FORCEPROP 1 LAST BODY_TYPE PLUMBING
J 2
(-2100 2800);
DISPLAY 0.872340 (-2100 2800);
PAINT GREEN (-2100 2800);
DISPLAY INVISIBLE (-2100 2800);
FORCEPROP 1 LAST HDL_TAP TRUE
J 2
(-2425 2625);
DISPLAY 0.872340 (-2425 2625);
DISPLAY INVISIBLE (-2425 2625);
FORCEPROP 1 LAST PATH I36
J 2
(-2098 2750);
DISPLAY 0.872340 (-2098 2750);
PAINT GREEN (-2098 2750);
DISPLAY INVISIBLE (-2098 2750);
FORCEADD TAP..1
R 2
(-2100 3600);
FORCEPROP 3 LASTPIN (-2050 3600) SIG_NAME M_C_CPU0_SB_CA<2>
J 0
(-2040 3610);
DISPLAY 0.659574 (-2040 3610);
PAINT MONO (-2040 3610);
DISPLAY INVISIBLE (-2040 3610);
FORCEPROP 1 LASTPIN (-2050 3600) BN 2
J 2
(-2038 3608);
DISPLAY 0.680851 (-2038 3608);
PAINT GREEN (-2038 3608);
FORCEPROP 2 LAST CDS_LIB standard
J 0
(-2100 3600);
DISPLAY INVISIBLE (-2100 3600);
FORCEPROP 1 LAST BODY_TYPE PLUMBING
J 2
(-2100 3650);
DISPLAY 0.872340 (-2100 3650);
PAINT GREEN (-2100 3650);
DISPLAY INVISIBLE (-2100 3650);
FORCEPROP 1 LAST HDL_TAP TRUE
J 2
(-2425 3475);
DISPLAY 0.872340 (-2425 3475);
DISPLAY INVISIBLE (-2425 3475);
FORCEPROP 1 LAST PATH I37
J 2
(-2098 3600);
DISPLAY 0.872340 (-2098 3600);
PAINT GREEN (-2098 3600);
DISPLAY INVISIBLE (-2098 3600);
FORCEADD TAP..1
R 2
(-2100 3500);
FORCEPROP 3 LASTPIN (-2050 3500) SIG_NAME M_C_CPU0_SB_CA<0>
J 0
(-2040 3510);
DISPLAY 0.659574 (-2040 3510);
PAINT MONO (-2040 3510);
DISPLAY INVISIBLE (-2040 3510);
FORCEPROP 1 LASTPIN (-2050 3500) BN 0
J 2
(-2038 3508);
DISPLAY 0.680851 (-2038 3508);
PAINT GREEN (-2038 3508);
FORCEPROP 2 LAST CDS_LIB standard
J 0
(-2100 3500);
DISPLAY INVISIBLE (-2100 3500);
FORCEPROP 1 LAST BODY_TYPE PLUMBING
J 2
(-2100 3550);
DISPLAY 0.872340 (-2100 3550);
PAINT GREEN (-2100 3550);
DISPLAY INVISIBLE (-2100 3550);
FORCEPROP 1 LAST HDL_TAP TRUE
J 2
(-2425 3375);
DISPLAY 0.872340 (-2425 3375);
DISPLAY INVISIBLE (-2425 3375);
FORCEPROP 1 LAST PATH I38
J 2
(-2098 3500);
DISPLAY 0.872340 (-2098 3500);
PAINT GREEN (-2098 3500);
DISPLAY INVISIBLE (-2098 3500);
FORCEADD TAP..1
R 2
(-2100 3550);
FORCEPROP 3 LASTPIN (-2050 3550) SIG_NAME M_C_CPU0_SB_CA<1>
J 0
(-2040 3560);
DISPLAY 0.659574 (-2040 3560);
PAINT MONO (-2040 3560);
DISPLAY INVISIBLE (-2040 3560);
FORCEPROP 1 LASTPIN (-2050 3550) BN 1
J 2
(-2038 3558);
DISPLAY 0.680851 (-2038 3558);
PAINT GREEN (-2038 3558);
FORCEPROP 2 LAST CDS_LIB standard
J 0
(-2100 3550);
DISPLAY INVISIBLE (-2100 3550);
FORCEPROP 1 LAST BODY_TYPE PLUMBING
J 2
(-2100 3600);
DISPLAY 0.872340 (-2100 3600);
PAINT GREEN (-2100 3600);
DISPLAY INVISIBLE (-2100 3600);
FORCEPROP 1 LAST HDL_TAP TRUE
J 2
(-2425 3425);
DISPLAY 0.872340 (-2425 3425);
DISPLAY INVISIBLE (-2425 3425);
FORCEPROP 1 LAST PATH I39
J 2
(-2098 3550);
DISPLAY 0.872340 (-2098 3550);
PAINT GREEN (-2098 3550);
DISPLAY INVISIBLE (-2098 3550);
FORCEADD TAP..1
R 2
(-2100 3800);
FORCEPROP 3 LASTPIN (-2050 3800) SIG_NAME M_C_CPU0_SB_CA<6>
J 0
(-2040 3810);
DISPLAY 0.659574 (-2040 3810);
PAINT MONO (-2040 3810);
DISPLAY INVISIBLE (-2040 3810);
FORCEPROP 1 LASTPIN (-2050 3800) BN 6
J 2
(-2038 3808);
DISPLAY 0.680851 (-2038 3808);
PAINT GREEN (-2038 3808);
FORCEPROP 2 LAST CDS_LIB standard
J 0
(-2100 3800);
DISPLAY INVISIBLE (-2100 3800);
FORCEPROP 1 LAST BODY_TYPE PLUMBING
J 2
(-2100 3850);
DISPLAY 0.872340 (-2100 3850);
PAINT GREEN (-2100 3850);
DISPLAY INVISIBLE (-2100 3850);
FORCEPROP 1 LAST HDL_TAP TRUE
J 2
(-2425 3675);
DISPLAY 0.872340 (-2425 3675);
DISPLAY INVISIBLE (-2425 3675);
FORCEPROP 1 LAST PATH I40
J 2
(-2098 3800);
DISPLAY 0.872340 (-2098 3800);
PAINT GREEN (-2098 3800);
DISPLAY INVISIBLE (-2098 3800);
FORCEADD TAP..1
R 2
(-2100 3700);
FORCEPROP 3 LASTPIN (-2050 3700) SIG_NAME M_C_CPU0_SB_CA<4>
J 0
(-2040 3710);
DISPLAY 0.659574 (-2040 3710);
PAINT MONO (-2040 3710);
DISPLAY INVISIBLE (-2040 3710);
FORCEPROP 1 LASTPIN (-2050 3700) BN 4
J 2
(-2038 3708);
DISPLAY 0.680851 (-2038 3708);
PAINT GREEN (-2038 3708);
FORCEPROP 2 LAST CDS_LIB standard
J 0
(-2100 3700);
DISPLAY INVISIBLE (-2100 3700);
FORCEPROP 1 LAST BODY_TYPE PLUMBING
J 2
(-2100 3750);
DISPLAY 0.872340 (-2100 3750);
PAINT GREEN (-2100 3750);
DISPLAY INVISIBLE (-2100 3750);
FORCEPROP 1 LAST HDL_TAP TRUE
J 2
(-2425 3575);
DISPLAY 0.872340 (-2425 3575);
DISPLAY INVISIBLE (-2425 3575);
FORCEPROP 1 LAST PATH I41
J 2
(-2098 3700);
DISPLAY 0.872340 (-2098 3700);
PAINT GREEN (-2098 3700);
DISPLAY INVISIBLE (-2098 3700);
FORCEADD TAP..1
R 2
(-2100 3650);
FORCEPROP 3 LASTPIN (-2050 3650) SIG_NAME M_C_CPU0_SB_CA<3>
J 0
(-2040 3660);
DISPLAY 0.659574 (-2040 3660);
PAINT MONO (-2040 3660);
DISPLAY INVISIBLE (-2040 3660);
FORCEPROP 1 LASTPIN (-2050 3650) BN 3
J 2
(-2038 3658);
DISPLAY 0.680851 (-2038 3658);
PAINT GREEN (-2038 3658);
FORCEPROP 2 LAST CDS_LIB standard
J 0
(-2100 3650);
DISPLAY INVISIBLE (-2100 3650);
FORCEPROP 1 LAST BODY_TYPE PLUMBING
J 2
(-2100 3700);
DISPLAY 0.872340 (-2100 3700);
PAINT GREEN (-2100 3700);
DISPLAY INVISIBLE (-2100 3700);
FORCEPROP 1 LAST HDL_TAP TRUE
J 2
(-2425 3525);
DISPLAY 0.872340 (-2425 3525);
DISPLAY INVISIBLE (-2425 3525);
FORCEPROP 1 LAST PATH I42
J 2
(-2098 3650);
DISPLAY 0.872340 (-2098 3650);
PAINT GREEN (-2098 3650);
DISPLAY INVISIBLE (-2098 3650);
FORCEADD TAP..1
R 2
(-2100 3750);
FORCEPROP 3 LASTPIN (-2050 3750) SIG_NAME M_C_CPU0_SB_CA<5>
J 0
(-2040 3760);
DISPLAY 0.659574 (-2040 3760);
PAINT MONO (-2040 3760);
DISPLAY INVISIBLE (-2040 3760);
FORCEPROP 1 LASTPIN (-2050 3750) BN 5
J 2
(-2038 3758);
DISPLAY 0.680851 (-2038 3758);
PAINT GREEN (-2038 3758);
FORCEPROP 2 LAST CDS_LIB standard
J 0
(-2100 3750);
DISPLAY INVISIBLE (-2100 3750);
FORCEPROP 1 LAST BODY_TYPE PLUMBING
J 2
(-2100 3800);
DISPLAY 0.872340 (-2100 3800);
PAINT GREEN (-2100 3800);
DISPLAY INVISIBLE (-2100 3800);
FORCEPROP 1 LAST HDL_TAP TRUE
J 2
(-2425 3625);
DISPLAY 0.872340 (-2425 3625);
DISPLAY INVISIBLE (-2425 3625);
FORCEPROP 1 LAST PATH I43
J 2
(-2098 3750);
DISPLAY 0.872340 (-2098 3750);
PAINT GREEN (-2098 3750);
DISPLAY INVISIBLE (-2098 3750);
FORCEADD UNIVERSAL_GND..1
(-1875 -175);
FORCEPROP 3 LASTPIN (-1875 -125) SIG_NAME GND\g
J 0
(-1865 -115);
DISPLAY 0.659574 (-1865 -115);
PAINT MONO (-1865 -115);
DISPLAY INVISIBLE (-1865 -115);
FORCEPROP 2 LAST CDS_LIB logical_power
J 0
(-1875 -175);
PAINT MONO (-1875 -175);
DISPLAY INVISIBLE (-1875 -175);
FORCEPROP 1 LAST HDL_POWER GND
J 1
(-1850 -250);
DISPLAY 0.872340 (-1850 -250);
PAINT GREEN (-1850 -250);
DISPLAY INVISIBLE (-1850 -250);
FORCEPROP 1 LAST PATH I44
J 0
(-1800 -175);
DISPLAY 0.872340 (-1800 -175);
PAINT AQUA (-1800 -175);
DISPLAY INVISIBLE (-1800 -175);
FORCEADD Q_RES..2
(-1875 50);
FORCEPROP 1 LAST PART_NUMBER CS38452FB05
J 0
(-1835 -75);
DISPLAY 0.978723 (-1835 -75);
DISPLAY INVISIBLE (-1835 -75);
FORCEPROP 1 LAST VALUE 84.5K
J 0
(-1830 125);
DISPLAY 0.978723 (-1830 125);
FORCEPROP 1 LAST PACK_TYPE 0402LF
J 0
(-1835 -125);
DISPLAY 0.978723 (-1835 -125);
FORCEPROP 1 LAST MATERIAL CHIP
J 0
(-1835 -25);
DISPLAY 0.978723 (-1835 -25);
FORCEPROP 1 LAST WATTAGE 1/16W
J 0
(-1835 25);
DISPLAY 0.978723 (-1835 25);
FORCEPROP 1 LAST TOLERANCE 1%
J 0
(-1830 75);
DISPLAY 0.978723 (-1830 75);
FORCEPROP 1 LAST $LOCATION R31
J 0
(-1830 175);
DISPLAY 0.978723 (-1830 175);
FORCEPROP 1 LASTPIN (-1875 150) $PN 1
J 0
(-1870 112);
DISPLAY 0.787234 (-1870 112);
FORCEPROP 1 LASTPIN (-1875 -50) $PN 2
J 0
(-1870 -40);
DISPLAY 0.787234 (-1870 -40);
FORCEPROP 2 LAST CDS_LIB pure_quanta
J 0
(-1875 50);
PAINT MONO (-1875 50);
DISPLAY INVISIBLE (-1875 50);
FORCEPROP 2 LAST CDS_LOCATION R31
J 0
(-1825 275);
DISPLAY 1.021277 (-1825 275);
DISPLAY INVISIBLE (-1825 275);
FORCEPROP 2 LAST $SEC 1
J 0
(-1825 275);
DISPLAY 0.680851 (-1825 275);
PAINT MONO (-1825 275);
DISPLAY INVISIBLE (-1825 275);
FORCEPROP 2 LAST CDS_SEC 1
J 0
(-1825 275);
DISPLAY 1.021277 (-1825 275);
DISPLAY INVISIBLE (-1825 275);
FORCEPROP 1 LAST PATH I45
J 0
(-1825 225);
DISPLAY 0.978723 (-1825 225);
PAINT WHITE (-1825 225);
DISPLAY INVISIBLE (-1825 225);
FORCEADD SCONN288_ADR50017P087CC..1
(-1275 2475);
FORCEPROP 1 LAST PART_NUMBER DFHST8FS460
J 0
(-1720 4485);
DISPLAY 0.723404 (-1720 4485);
PAINT GREEN (-1720 4485);
DISPLAY INVISIBLE (-1720 4485);
FORCEPROP 1 LAST MATERIAL IO
J 0
(-1720 4358);
DISPLAY 0.723404 (-1720 4358);
PAINT GREEN (-1720 4358);
FORCEPROP 2 LAST PART_TYPE SMLF
J 0
(-1725 4650);
DISPLAY 1.021277 (-1725 4650);
FORCEPROP 2 LAST VALUE SCONN288_ADR50017-P087CC
J 0
(-1725 4600);
DISPLAY 1.021277 (-1725 4600);
FORCEPROP 1 LAST $LOCATION J6
J 0
(-1725 4550);
DISPLAY 0.723404 (-1725 4550);
PAINT GREEN (-1725 4550);
FORCEPROP 0 LASTPIN (-1875 1850) $PN 62
J 2
(-1885 1860);
DISPLAY 0.680851 (-1885 1860);
PAINT MONO (-1885 1860);
FORCEPROP 0 LASTPIN (-1875 3900) $PN 66
J 2
(-1885 3910);
DISPLAY 0.680851 (-1885 3910);
PAINT MONO (-1885 3910);
FORCEPROP 0 LASTPIN (-1875 3500) $PN 76
J 2
(-1885 3510);
DISPLAY 0.680851 (-1885 3510);
PAINT MONO (-1885 3510);
FORCEPROP 0 LASTPIN (-1875 3950) $PN 211
J 2
(-1885 3960);
DISPLAY 0.680851 (-1885 3960);
PAINT MONO (-1885 3960);
FORCEPROP 0 LASTPIN (-1875 3550) $PN 221
J 2
(-1885 3560);
DISPLAY 0.680851 (-1885 3560);
PAINT MONO (-1885 3560);
FORCEPROP 0 LASTPIN (-1875 4000) $PN 68
J 2
(-1885 4010);
DISPLAY 0.680851 (-1885 4010);
PAINT MONO (-1885 4010);
FORCEPROP 0 LASTPIN (-1875 3600) $PN 78
J 2
(-1885 3610);
DISPLAY 0.680851 (-1885 3610);
PAINT MONO (-1885 3610);
FORCEPROP 0 LASTPIN (-1875 4050) $PN 213
J 2
(-1885 4060);
DISPLAY 0.680851 (-1885 4060);
PAINT MONO (-1885 4060);
FORCEPROP 0 LASTPIN (-1875 3650) $PN 223
J 2
(-1885 3660);
DISPLAY 0.680851 (-1885 3660);
PAINT MONO (-1885 3660);
FORCEPROP 0 LASTPIN (-1875 4100) $PN 70
J 2
(-1885 4110);
DISPLAY 0.680851 (-1885 4110);
PAINT MONO (-1885 4110);
FORCEPROP 0 LASTPIN (-1875 3700) $PN 80
J 2
(-1885 3710);
DISPLAY 0.680851 (-1885 3710);
PAINT MONO (-1885 3710);
FORCEPROP 0 LASTPIN (-1875 4150) $PN 215
J 2
(-1885 4160);
DISPLAY 0.680851 (-1885 4160);
PAINT MONO (-1885 4160);
FORCEPROP 0 LASTPIN (-1875 3750) $PN 225
J 2
(-1885 3760);
DISPLAY 0.680851 (-1885 3760);
PAINT MONO (-1885 3760);
FORCEPROP 0 LASTPIN (-1875 4200) $PN 72
J 2
(-1885 4210);
DISPLAY 0.680851 (-1885 4210);
PAINT MONO (-1885 4210);
FORCEPROP 0 LASTPIN (-1875 3800) $PN 82
J 2
(-1885 3810);
DISPLAY 0.680851 (-1885 3810);
PAINT MONO (-1885 3810);
FORCEPROP 0 LASTPIN (-1875 2450) $PN 51
J 2
(-1885 2460);
DISPLAY 0.680851 (-1885 2460);
PAINT MONO (-1885 2460);
FORCEPROP 0 LASTPIN (-1875 2000) $PN 96
J 2
(-1885 2010);
DISPLAY 0.680851 (-1885 2010);
PAINT MONO (-1885 2010);
FORCEPROP 0 LASTPIN (-1875 2500) $PN 53
J 2
(-1885 2510);
DISPLAY 0.680851 (-1885 2510);
PAINT MONO (-1885 2510);
FORCEPROP 0 LASTPIN (-1875 2050) $PN 98
J 2
(-1885 2060);
DISPLAY 0.680851 (-1885 2060);
PAINT MONO (-1885 2060);
FORCEPROP 0 LASTPIN (-1875 2550) $PN 196
J 2
(-1885 2560);
DISPLAY 0.680851 (-1885 2560);
PAINT MONO (-1885 2560);
FORCEPROP 0 LASTPIN (-1875 2100) $PN 241
J 2
(-1885 2110);
DISPLAY 0.680851 (-1885 2110);
PAINT MONO (-1885 2110);
FORCEPROP 0 LASTPIN (-1875 2600) $PN 198
J 2
(-1885 2610);
DISPLAY 0.680851 (-1885 2610);
PAINT MONO (-1885 2610);
FORCEPROP 0 LASTPIN (-1875 2150) $PN 243
J 2
(-1885 2160);
DISPLAY 0.680851 (-1885 2160);
PAINT MONO (-1885 2160);
FORCEPROP 0 LASTPIN (-1875 2650) $PN 58
J 2
(-1885 2660);
DISPLAY 0.680851 (-1885 2660);
PAINT MONO (-1885 2660);
FORCEPROP 0 LASTPIN (-1875 2200) $PN 89
J 2
(-1885 2210);
DISPLAY 0.680851 (-1885 2210);
PAINT MONO (-1885 2210);
FORCEPROP 0 LASTPIN (-1875 2700) $PN 60
J 2
(-1885 2710);
DISPLAY 0.680851 (-1885 2710);
PAINT MONO (-1885 2710);
FORCEPROP 0 LASTPIN (-1875 2250) $PN 91
J 2
(-1885 2260);
DISPLAY 0.680851 (-1885 2260);
PAINT MONO (-1885 2260);
FORCEPROP 0 LASTPIN (-1875 2750) $PN 203
J 2
(-1885 2760);
DISPLAY 0.680851 (-1885 2760);
PAINT MONO (-1885 2760);
FORCEPROP 0 LASTPIN (-1875 2300) $PN 234
J 2
(-1885 2310);
DISPLAY 0.680851 (-1885 2310);
PAINT MONO (-1885 2310);
FORCEPROP 0 LASTPIN (-1875 2800) $PN 205
J 2
(-1885 2810);
DISPLAY 0.680851 (-1885 2810);
PAINT MONO (-1885 2810);
FORCEPROP 0 LASTPIN (-1875 2350) $PN 236
J 2
(-1885 2360);
DISPLAY 0.680851 (-1885 2360);
PAINT MONO (-1885 2360);
FORCEPROP 0 LASTPIN (-1875 2900) $PN 218
J 2
(-1885 2910);
DISPLAY 0.680851 (-1885 2910);
PAINT MONO (-1885 2910);
FORCEPROP 0 LASTPIN (-1875 2950) $PN 217
J 2
(-1885 2960);
DISPLAY 0.680851 (-1885 2960);
PAINT MONO (-1885 2960);
FORCEPROP 0 LASTPIN (-1875 3200) $PN 64
J 2
(-1885 3210);
DISPLAY 0.680851 (-1885 3210);
PAINT MONO (-1885 3210);
FORCEPROP 0 LASTPIN (-1875 3050) $PN 84
J 2
(-1885 3060);
DISPLAY 0.680851 (-1885 3060);
PAINT MONO (-1885 3060);
FORCEPROP 0 LASTPIN (-1875 3250) $PN 209
J 2
(-1885 3260);
DISPLAY 0.680851 (-1885 3260);
PAINT MONO (-1885 3260);
FORCEPROP 0 LASTPIN (-1875 3100) $PN 229
J 2
(-1885 3110);
DISPLAY 0.680851 (-1885 3110);
PAINT MONO (-1885 3110);
FORCEPROP 0 LASTPIN (-675 2650) $PN 7
J 0
(-665 2660);
DISPLAY 0.680851 (-665 2660);
PAINT MONO (-665 2660);
FORCEPROP 0 LASTPIN (-675 1000) $PN 100
J 0
(-665 1010);
DISPLAY 0.680851 (-665 1010);
PAINT MONO (-665 1010);
FORCEPROP 0 LASTPIN (-675 2700) $PN 9
J 0
(-665 2710);
DISPLAY 0.680851 (-665 2710);
PAINT MONO (-665 2710);
FORCEPROP 0 LASTPIN (-675 1050) $PN 102
J 0
(-665 1060);
DISPLAY 0.680851 (-665 1060);
PAINT MONO (-665 1060);
FORCEPROP 0 LASTPIN (-675 2750) $PN 152
J 0
(-665 2760);
DISPLAY 0.680851 (-665 2760);
PAINT MONO (-665 2760);
FORCEPROP 0 LASTPIN (-675 1100) $PN 245
J 0
(-665 1110);
DISPLAY 0.680851 (-665 1110);
PAINT MONO (-665 1110);
FORCEPROP 0 LASTPIN (-675 2800) $PN 154
J 0
(-665 2810);
DISPLAY 0.680851 (-665 2810);
PAINT MONO (-665 2810);
FORCEPROP 0 LASTPIN (-675 1150) $PN 247
J 0
(-665 1160);
DISPLAY 0.680851 (-665 1160);
PAINT MONO (-665 1160);
FORCEPROP 0 LASTPIN (-675 2850) $PN 14
J 0
(-665 2860);
DISPLAY 0.680851 (-665 2860);
PAINT MONO (-665 2860);
FORCEPROP 0 LASTPIN (-675 1200) $PN 107
J 0
(-665 1210);
DISPLAY 0.680851 (-665 1210);
PAINT MONO (-665 1210);
FORCEPROP 0 LASTPIN (-675 2900) $PN 16
J 0
(-665 2910);
DISPLAY 0.680851 (-665 2910);
PAINT MONO (-665 2910);
FORCEPROP 0 LASTPIN (-675 1250) $PN 109
J 0
(-665 1260);
DISPLAY 0.680851 (-665 1260);
PAINT MONO (-665 1260);
FORCEPROP 0 LASTPIN (-675 2950) $PN 159
J 0
(-665 2960);
DISPLAY 0.680851 (-665 2960);
PAINT MONO (-665 2960);
FORCEPROP 0 LASTPIN (-675 1300) $PN 252
J 0
(-665 1310);
DISPLAY 0.680851 (-665 1310);
PAINT MONO (-665 1310);
FORCEPROP 0 LASTPIN (-675 3000) $PN 161
J 0
(-665 3010);
DISPLAY 0.680851 (-665 3010);
PAINT MONO (-665 3010);
FORCEPROP 0 LASTPIN (-675 1350) $PN 254
J 0
(-665 1360);
DISPLAY 0.680851 (-665 1360);
PAINT MONO (-665 1360);
FORCEPROP 0 LASTPIN (-675 3050) $PN 18
J 0
(-665 3060);
DISPLAY 0.680851 (-665 3060);
PAINT MONO (-665 3060);
FORCEPROP 0 LASTPIN (-675 1400) $PN 111
J 0
(-665 1410);
DISPLAY 0.680851 (-665 1410);
PAINT MONO (-665 1410);
FORCEPROP 0 LASTPIN (-675 3100) $PN 20
J 0
(-665 3110);
DISPLAY 0.680851 (-665 3110);
PAINT MONO (-665 3110);
FORCEPROP 0 LASTPIN (-675 1450) $PN 113
J 0
(-665 1460);
DISPLAY 0.680851 (-665 1460);
PAINT MONO (-665 1460);
FORCEPROP 0 LASTPIN (-675 3150) $PN 163
J 0
(-665 3160);
DISPLAY 0.680851 (-665 3160);
PAINT MONO (-665 3160);
FORCEPROP 0 LASTPIN (-675 1500) $PN 256
J 0
(-665 1510);
DISPLAY 0.680851 (-665 1510);
PAINT MONO (-665 1510);
FORCEPROP 0 LASTPIN (-675 3200) $PN 165
J 0
(-665 3210);
DISPLAY 0.680851 (-665 3210);
PAINT MONO (-665 3210);
FORCEPROP 0 LASTPIN (-675 1550) $PN 258
J 0
(-665 1560);
DISPLAY 0.680851 (-665 1560);
PAINT MONO (-665 1560);
FORCEPROP 0 LASTPIN (-675 3250) $PN 25
J 0
(-665 3260);
DISPLAY 0.680851 (-665 3260);
PAINT MONO (-665 3260);
FORCEPROP 0 LASTPIN (-675 1600) $PN 118
J 0
(-665 1610);
DISPLAY 0.680851 (-665 1610);
PAINT MONO (-665 1610);
FORCEPROP 0 LASTPIN (-675 3300) $PN 27
J 0
(-665 3310);
DISPLAY 0.680851 (-665 3310);
PAINT MONO (-665 3310);
FORCEPROP 0 LASTPIN (-675 1650) $PN 120
J 0
(-665 1660);
DISPLAY 0.680851 (-665 1660);
PAINT MONO (-665 1660);
FORCEPROP 0 LASTPIN (-675 3350) $PN 170
J 0
(-665 3360);
DISPLAY 0.680851 (-665 3360);
PAINT MONO (-665 3360);
FORCEPROP 0 LASTPIN (-675 1700) $PN 263
J 0
(-665 1710);
DISPLAY 0.680851 (-665 1710);
PAINT MONO (-665 1710);
FORCEPROP 0 LASTPIN (-675 3400) $PN 172
J 0
(-665 3410);
DISPLAY 0.680851 (-665 3410);
PAINT MONO (-665 3410);
FORCEPROP 0 LASTPIN (-675 1750) $PN 265
J 0
(-665 1760);
DISPLAY 0.680851 (-665 1760);
PAINT MONO (-665 1760);
FORCEPROP 0 LASTPIN (-675 3450) $PN 29
J 0
(-665 3460);
DISPLAY 0.680851 (-665 3460);
PAINT MONO (-665 3460);
FORCEPROP 0 LASTPIN (-675 1800) $PN 122
J 0
(-665 1810);
DISPLAY 0.680851 (-665 1810);
PAINT MONO (-665 1810);
FORCEPROP 0 LASTPIN (-675 3500) $PN 31
J 0
(-665 3510);
DISPLAY 0.680851 (-665 3510);
PAINT MONO (-665 3510);
FORCEPROP 0 LASTPIN (-675 1850) $PN 124
J 0
(-665 1860);
DISPLAY 0.680851 (-665 1860);
PAINT MONO (-665 1860);
FORCEPROP 0 LASTPIN (-675 3550) $PN 174
J 0
(-665 3560);
DISPLAY 0.680851 (-665 3560);
PAINT MONO (-665 3560);
FORCEPROP 0 LASTPIN (-675 1900) $PN 267
J 0
(-665 1910);
DISPLAY 0.680851 (-665 1910);
PAINT MONO (-665 1910);
FORCEPROP 0 LASTPIN (-675 3600) $PN 176
J 0
(-665 3610);
DISPLAY 0.680851 (-665 3610);
PAINT MONO (-665 3610);
FORCEPROP 0 LASTPIN (-675 1950) $PN 269
J 0
(-665 1960);
DISPLAY 0.680851 (-665 1960);
PAINT MONO (-665 1960);
FORCEPROP 0 LASTPIN (-675 3650) $PN 36
J 0
(-665 3660);
DISPLAY 0.680851 (-665 3660);
PAINT MONO (-665 3660);
FORCEPROP 0 LASTPIN (-675 2000) $PN 129
J 0
(-665 2010);
DISPLAY 0.680851 (-665 2010);
PAINT MONO (-665 2010);
FORCEPROP 0 LASTPIN (-675 3700) $PN 38
J 0
(-665 3710);
DISPLAY 0.680851 (-665 3710);
PAINT MONO (-665 3710);
FORCEPROP 0 LASTPIN (-675 2050) $PN 131
J 0
(-665 2060);
DISPLAY 0.680851 (-665 2060);
PAINT MONO (-665 2060);
FORCEPROP 0 LASTPIN (-675 3750) $PN 181
J 0
(-665 3760);
DISPLAY 0.680851 (-665 3760);
PAINT MONO (-665 3760);
FORCEPROP 0 LASTPIN (-675 2100) $PN 274
J 0
(-665 2110);
DISPLAY 0.680851 (-665 2110);
PAINT MONO (-665 2110);
FORCEPROP 0 LASTPIN (-675 3800) $PN 183
J 0
(-665 3810);
DISPLAY 0.680851 (-665 3810);
PAINT MONO (-665 3810);
FORCEPROP 0 LASTPIN (-675 2150) $PN 276
J 0
(-665 2160);
DISPLAY 0.680851 (-665 2160);
PAINT MONO (-665 2160);
FORCEPROP 0 LASTPIN (-675 3850) $PN 40
J 0
(-665 3860);
DISPLAY 0.680851 (-665 3860);
PAINT MONO (-665 3860);
FORCEPROP 0 LASTPIN (-675 2200) $PN 133
J 0
(-665 2210);
DISPLAY 0.680851 (-665 2210);
PAINT MONO (-665 2210);
FORCEPROP 0 LASTPIN (-675 3900) $PN 42
J 0
(-665 3910);
DISPLAY 0.680851 (-665 3910);
PAINT MONO (-665 3910);
FORCEPROP 0 LASTPIN (-675 2250) $PN 135
J 0
(-665 2260);
DISPLAY 0.680851 (-665 2260);
PAINT MONO (-665 2260);
FORCEPROP 0 LASTPIN (-675 3950) $PN 185
J 0
(-665 3960);
DISPLAY 0.680851 (-665 3960);
PAINT MONO (-665 3960);
FORCEPROP 0 LASTPIN (-675 2300) $PN 278
J 0
(-665 2310);
DISPLAY 0.680851 (-665 2310);
PAINT MONO (-665 2310);
FORCEPROP 0 LASTPIN (-675 4000) $PN 187
J 0
(-665 4010);
DISPLAY 0.680851 (-665 4010);
PAINT MONO (-665 4010);
FORCEPROP 0 LASTPIN (-675 2350) $PN 280
J 0
(-665 2360);
DISPLAY 0.680851 (-665 2360);
PAINT MONO (-665 2360);
FORCEPROP 0 LASTPIN (-675 4050) $PN 47
J 0
(-665 4060);
DISPLAY 0.680851 (-665 4060);
PAINT MONO (-665 4060);
FORCEPROP 0 LASTPIN (-675 2400) $PN 140
J 0
(-665 2410);
DISPLAY 0.680851 (-665 2410);
PAINT MONO (-665 2410);
FORCEPROP 0 LASTPIN (-675 4100) $PN 49
J 0
(-665 4110);
DISPLAY 0.680851 (-665 4110);
PAINT MONO (-665 4110);
FORCEPROP 0 LASTPIN (-675 2450) $PN 142
J 0
(-665 2460);
DISPLAY 0.680851 (-665 2460);
PAINT MONO (-665 2460);
FORCEPROP 0 LASTPIN (-675 4150) $PN 192
J 0
(-665 4160);
DISPLAY 0.680851 (-665 4160);
PAINT MONO (-665 4160);
FORCEPROP 0 LASTPIN (-675 2500) $PN 285
J 0
(-665 2510);
DISPLAY 0.680851 (-665 2510);
PAINT MONO (-665 2510);
FORCEPROP 0 LASTPIN (-675 4200) $PN 194
J 0
(-665 4210);
DISPLAY 0.680851 (-665 4210);
PAINT MONO (-665 4210);
FORCEPROP 0 LASTPIN (-675 2550) $PN 287
J 0
(-665 2560);
DISPLAY 0.680851 (-665 2560);
PAINT MONO (-665 2560);
FORCEPROP 0 LASTPIN (-1875 1700) $PN 148
J 2
(-1885 1710);
DISPLAY 0.680851 (-1885 1710);
PAINT MONO (-1885 1710);
FORCEPROP 0 LASTPIN (-1875 1600) $PN 4
J 2
(-1885 1610);
DISPLAY 0.680851 (-1885 1610);
PAINT MONO (-1885 1610);
FORCEPROP 0 LASTPIN (-1875 1650) $PN 5
J 2
(-1885 1660);
DISPLAY 0.680851 (-1885 1660);
PAINT MONO (-1885 1660);
FORCEPROP 0 LASTPIN (-1875 800) $PN 86
J 2
(-1885 810);
DISPLAY 0.680851 (-1885 810);
PAINT MONO (-1885 810);
FORCEPROP 0 LASTPIN (-1875 750) $PN 87
J 2
(-1885 760);
DISPLAY 0.680851 (-1885 760);
PAINT MONO (-1885 760);
FORCEPROP 0 LASTPIN (-1875 3400) $PN 74
J 2
(-1885 3410);
DISPLAY 0.680851 (-1885 3410);
PAINT MONO (-1885 3410);
FORCEPROP 0 LASTPIN (-1875 3350) $PN 227
J 2
(-1885 3360);
DISPLAY 0.680851 (-1885 3360);
PAINT MONO (-1885 3360);
FORCEPROP 0 LASTPIN (-1875 1350) $PN 147
J 2
(-1885 1360);
DISPLAY 0.680851 (-1885 1360);
PAINT MONO (-1885 1360);
FORCEPROP 0 LASTPIN (-1875 1900) $PN 207
J 2
(-1885 1910);
DISPLAY 0.680851 (-1885 1910);
PAINT MONO (-1885 1910);
FORCEPROP 0 LASTPIN (-1875 950) $PN 2
J 2
(-1885 960);
DISPLAY 0.680851 (-1885 960);
PAINT MONO (-1885 960);
FORCEPROP 0 LASTPIN (-1875 1000) $PN 144
J 2
(-1885 1010);
DISPLAY 0.680851 (-1885 1010);
PAINT MONO (-1885 1010);
FORCEPROP 0 LASTPIN (-1875 1050) $PN 149
J 2
(-1885 1060);
DISPLAY 0.680851 (-1885 1060);
PAINT MONO (-1885 1060);
FORCEPROP 0 LASTPIN (-1875 1100) $PN 150
J 2
(-1885 1110);
DISPLAY 0.680851 (-1885 1110);
PAINT MONO (-1885 1110);
FORCEPROP 0 LASTPIN (-1875 1150) $PN 220
J 2
(-1885 1160);
DISPLAY 0.680851 (-1885 1160);
PAINT MONO (-1885 1160);
FORCEPROP 0 LASTPIN (-1875 1200) $PN 231
J 2
(-1885 1210);
DISPLAY 0.680851 (-1885 1210);
PAINT MONO (-1885 1210);
FORCEPROP 0 LASTPIN (-1875 1250) $PN 232
J 2
(-1885 1260);
DISPLAY 0.680851 (-1885 1260);
PAINT MONO (-1885 1260);
FORCEPROP 0 LASTPIN (-1875 1750) $PN 3
J 2
(-1885 1760);
DISPLAY 0.680851 (-1885 1760);
PAINT MONO (-1885 1760);
FORCEPROP 1 LAST NEEDS_NO_SIZE TRUE
J 0
(-1275 2475);
DISPLAY 0.723404 (-1275 2475);
PAINT GREEN (-1275 2475);
DISPLAY INVISIBLE (-1275 2475);
FORCEPROP 1 LAST CDS_LMAN_SYM_OUTLINE -450,1875,450,-1875
J 0
(-1275 2475);
DISPLAY 0.468085 (-1275 2475);
PAINT GREEN (-1275 2475);
DISPLAY INVISIBLE (-1275 2475);
FORCEPROP 2 LAST CDS_LIB pure_quanta
J 0
(-1275 2475);
DISPLAY INVISIBLE (-1275 2475);
FORCEPROP 2 LAST CDS_LOCATION J6
J 0
(-1725 4700);
DISPLAY 1.021277 (-1725 4700);
DISPLAY INVISIBLE (-1725 4700);
FORCEPROP 0 LAST $SEC 1
J 0
(-1725 4700);
DISPLAY 0.680851 (-1725 4700);
PAINT MONO (-1725 4700);
DISPLAY INVISIBLE (-1725 4700);
FORCEPROP 2 LAST CDS_SEC 1
J 0
(-1725 4700);
DISPLAY 1.021277 (-1725 4700);
DISPLAY INVISIBLE (-1725 4700);
FORCEPROP 1 LAST PATH I46
J 0
(-1275 2475);
DISPLAY 0.723404 (-1275 2475);
PAINT GREEN (-1275 2475);
DISPLAY INVISIBLE (-1275 2475);
FORCEADD TAP..1
(-450 1050);
FORCEPROP 3 LASTPIN (-500 1050) SIG_NAME M_C_CPU0_SB_DQ<1>
J 0
(-490 1060);
DISPLAY 0.659574 (-490 1060);
PAINT MONO (-490 1060);
DISPLAY INVISIBLE (-490 1060);
FORCEPROP 1 LASTPIN (-500 1050) BN 1
J 0
(-512 1058);
DISPLAY 0.680851 (-512 1058);
PAINT GREEN (-512 1058);
FORCEPROP 2 LAST CDS_LIB standard
J 0
(-450 1050);
PAINT MONO (-450 1050);
DISPLAY INVISIBLE (-450 1050);
FORCEPROP 1 LAST BODY_TYPE PLUMBING
J 0
(-450 1100);
DISPLAY 0.872340 (-450 1100);
PAINT GREEN (-450 1100);
DISPLAY INVISIBLE (-450 1100);
FORCEPROP 1 LAST HDL_TAP TRUE
J 0
(-125 925);
DISPLAY 0.872340 (-125 925);
DISPLAY INVISIBLE (-125 925);
FORCEPROP 1 LAST PATH I47
J 0
(-452 1050);
DISPLAY 0.872340 (-452 1050);
PAINT GREEN (-452 1050);
DISPLAY INVISIBLE (-452 1050);
FORCEADD TAP..1
(-450 1000);
FORCEPROP 3 LASTPIN (-500 1000) SIG_NAME M_C_CPU0_SB_DQ<0>
J 0
(-490 1010);
DISPLAY 0.659574 (-490 1010);
PAINT MONO (-490 1010);
DISPLAY INVISIBLE (-490 1010);
FORCEPROP 1 LASTPIN (-500 1000) BN 0
J 0
(-512 1008);
DISPLAY 0.680851 (-512 1008);
PAINT GREEN (-512 1008);
FORCEPROP 2 LAST CDS_LIB standard
J 0
(-450 1000);
PAINT MONO (-450 1000);
DISPLAY INVISIBLE (-450 1000);
FORCEPROP 1 LAST BODY_TYPE PLUMBING
J 0
(-450 1050);
DISPLAY 0.872340 (-450 1050);
PAINT GREEN (-450 1050);
DISPLAY INVISIBLE (-450 1050);
FORCEPROP 1 LAST HDL_TAP TRUE
J 0
(-125 875);
DISPLAY 0.872340 (-125 875);
DISPLAY INVISIBLE (-125 875);
FORCEPROP 1 LAST PATH I48
J 0
(-452 1000);
DISPLAY 0.872340 (-452 1000);
PAINT GREEN (-452 1000);
DISPLAY INVISIBLE (-452 1000);
FORCEADD TAP..1
(-450 1100);
FORCEPROP 3 LASTPIN (-500 1100) SIG_NAME M_C_CPU0_SB_DQ<2>
J 0
(-490 1110);
DISPLAY 0.659574 (-490 1110);
PAINT MONO (-490 1110);
DISPLAY INVISIBLE (-490 1110);
FORCEPROP 1 LASTPIN (-500 1100) BN 2
J 0
(-512 1108);
DISPLAY 0.680851 (-512 1108);
PAINT GREEN (-512 1108);
FORCEPROP 2 LAST CDS_LIB standard
J 0
(-450 1100);
PAINT MONO (-450 1100);
DISPLAY INVISIBLE (-450 1100);
FORCEPROP 1 LAST BODY_TYPE PLUMBING
J 0
(-450 1150);
DISPLAY 0.872340 (-450 1150);
PAINT GREEN (-450 1150);
DISPLAY INVISIBLE (-450 1150);
FORCEPROP 1 LAST HDL_TAP TRUE
J 0
(-125 975);
DISPLAY 0.872340 (-125 975);
DISPLAY INVISIBLE (-125 975);
FORCEPROP 1 LAST PATH I49
J 0
(-452 1100);
DISPLAY 0.872340 (-452 1100);
PAINT GREEN (-452 1100);
DISPLAY INVISIBLE (-452 1100);
FORCEADD OFFPAGE..1
(-2950 1650);
FORCEPROP 2 LAST $XR7 89 
J 0
(-3412 1686);
DISPLAY 0.638298 (-3412 1686);
PAINT MONO (-3412 1686);
FORCEPROP 2 LAST $XR6 88 
J 0
(-3322 1686);
DISPLAY 0.638298 (-3322 1686);
PAINT MONO (-3322 1686);
FORCEPROP 2 LAST $XR5 86 
J 0
(-3412 1614);
DISPLAY 0.638298 (-3412 1614);
PAINT MONO (-3412 1614);
FORCEPROP 2 LAST $XR4 85 
J 0
(-3322 1614);
DISPLAY 0.638298 (-3322 1614);
PAINT MONO (-3322 1614);
FORCEPROP 2 LAST $XR3 84 
J 0
(-3232 1614);
DISPLAY 0.638298 (-3232 1614);
PAINT MONO (-3232 1614);
FORCEPROP 2 LAST $XR2 83 
J 0
(-3412 1650);
DISPLAY 0.638298 (-3412 1650);
PAINT MONO (-3412 1650);
FORCEPROP 2 LAST $XR1 82 
J 0
(-3322 1650);
DISPLAY 0.638298 (-3322 1650);
PAINT MONO (-3322 1650);
FORCEPROP 2 LAST $XR0 229 
J 0
(-3232 1650);
DISPLAY 0.638298 (-3232 1650);
PAINT MONO (-3232 1650);
FORCEPROP 2 LAST CDS_LIB standard
J 0
(-2950 1650);
PAINT MONO (-2950 1650);
DISPLAY INVISIBLE (-2950 1650);
FORCEPROP 1 LAST OFFPAGE TRUE
J 0
(-2625 1525);
DISPLAY 0.872340 (-2625 1525);
DISPLAY INVISIBLE (-2625 1525);
FORCEPROP 1 LAST COMMENT_BODY TRUE
J 0
(-2825 1550);
DISPLAY 0.872340 (-2825 1550);
PAINT GREEN (-2825 1550);
DISPLAY INVISIBLE (-2825 1550);
FORCEPROP 2 LAST PATH I5
J 0
(-2900 1725);
DISPLAY 1.021277 (-2900 1725);
DISPLAY INVISIBLE (-2900 1725);
FORCEADD TAP..1
(-450 1200);
FORCEPROP 3 LASTPIN (-500 1200) SIG_NAME M_C_CPU0_SB_DQ<4>
J 0
(-490 1210);
DISPLAY 0.659574 (-490 1210);
PAINT MONO (-490 1210);
DISPLAY INVISIBLE (-490 1210);
FORCEPROP 1 LASTPIN (-500 1200) BN 4
J 0
(-512 1208);
DISPLAY 0.680851 (-512 1208);
PAINT GREEN (-512 1208);
FORCEPROP 2 LAST CDS_LIB standard
J 0
(-450 1200);
PAINT MONO (-450 1200);
DISPLAY INVISIBLE (-450 1200);
FORCEPROP 1 LAST BODY_TYPE PLUMBING
J 0
(-450 1250);
DISPLAY 0.872340 (-450 1250);
PAINT GREEN (-450 1250);
DISPLAY INVISIBLE (-450 1250);
FORCEPROP 1 LAST HDL_TAP TRUE
J 0
(-125 1075);
DISPLAY 0.872340 (-125 1075);
DISPLAY INVISIBLE (-125 1075);
FORCEPROP 1 LAST PATH I50
J 0
(-452 1200);
DISPLAY 0.872340 (-452 1200);
PAINT GREEN (-452 1200);
DISPLAY INVISIBLE (-452 1200);
FORCEADD TAP..1
(-450 1150);
FORCEPROP 3 LASTPIN (-500 1150) SIG_NAME M_C_CPU0_SB_DQ<3>
J 0
(-490 1160);
DISPLAY 0.659574 (-490 1160);
PAINT MONO (-490 1160);
DISPLAY INVISIBLE (-490 1160);
FORCEPROP 1 LASTPIN (-500 1150) BN 3
J 0
(-512 1158);
DISPLAY 0.680851 (-512 1158);
PAINT GREEN (-512 1158);
FORCEPROP 2 LAST CDS_LIB standard
J 0
(-450 1150);
PAINT MONO (-450 1150);
DISPLAY INVISIBLE (-450 1150);
FORCEPROP 1 LAST BODY_TYPE PLUMBING
J 0
(-450 1200);
DISPLAY 0.872340 (-450 1200);
PAINT GREEN (-450 1200);
DISPLAY INVISIBLE (-450 1200);
FORCEPROP 1 LAST HDL_TAP TRUE
J 0
(-125 1025);
DISPLAY 0.872340 (-125 1025);
DISPLAY INVISIBLE (-125 1025);
FORCEPROP 1 LAST PATH I51
J 0
(-452 1150);
DISPLAY 0.872340 (-452 1150);
PAINT GREEN (-452 1150);
DISPLAY INVISIBLE (-452 1150);
FORCEADD TAP..1
(-450 1300);
FORCEPROP 3 LASTPIN (-500 1300) SIG_NAME M_C_CPU0_SB_DQ<6>
J 0
(-490 1310);
DISPLAY 0.659574 (-490 1310);
PAINT MONO (-490 1310);
DISPLAY INVISIBLE (-490 1310);
FORCEPROP 1 LASTPIN (-500 1300) BN 6
J 0
(-512 1308);
DISPLAY 0.680851 (-512 1308);
PAINT GREEN (-512 1308);
FORCEPROP 2 LAST CDS_LIB standard
J 0
(-450 1300);
PAINT MONO (-450 1300);
DISPLAY INVISIBLE (-450 1300);
FORCEPROP 1 LAST BODY_TYPE PLUMBING
J 0
(-450 1350);
DISPLAY 0.872340 (-450 1350);
PAINT GREEN (-450 1350);
DISPLAY INVISIBLE (-450 1350);
FORCEPROP 1 LAST HDL_TAP TRUE
J 0
(-125 1175);
DISPLAY 0.872340 (-125 1175);
DISPLAY INVISIBLE (-125 1175);
FORCEPROP 1 LAST PATH I52
J 0
(-452 1300);
DISPLAY 0.872340 (-452 1300);
PAINT GREEN (-452 1300);
DISPLAY INVISIBLE (-452 1300);
FORCEADD TAP..1
(-450 1250);
FORCEPROP 3 LASTPIN (-500 1250) SIG_NAME M_C_CPU0_SB_DQ<5>
J 0
(-490 1260);
DISPLAY 0.659574 (-490 1260);
PAINT MONO (-490 1260);
DISPLAY INVISIBLE (-490 1260);
FORCEPROP 1 LASTPIN (-500 1250) BN 5
J 0
(-512 1258);
DISPLAY 0.680851 (-512 1258);
PAINT GREEN (-512 1258);
FORCEPROP 2 LAST CDS_LIB standard
J 0
(-450 1250);
PAINT MONO (-450 1250);
DISPLAY INVISIBLE (-450 1250);
FORCEPROP 1 LAST BODY_TYPE PLUMBING
J 0
(-450 1300);
DISPLAY 0.872340 (-450 1300);
PAINT GREEN (-450 1300);
DISPLAY INVISIBLE (-450 1300);
FORCEPROP 1 LAST HDL_TAP TRUE
J 0
(-125 1125);
DISPLAY 0.872340 (-125 1125);
DISPLAY INVISIBLE (-125 1125);
FORCEPROP 1 LAST PATH I53
J 0
(-452 1250);
DISPLAY 0.872340 (-452 1250);
PAINT GREEN (-452 1250);
DISPLAY INVISIBLE (-452 1250);
FORCEADD TAP..1
(-450 1350);
FORCEPROP 3 LASTPIN (-500 1350) SIG_NAME M_C_CPU0_SB_DQ<7>
J 0
(-490 1360);
DISPLAY 0.659574 (-490 1360);
PAINT MONO (-490 1360);
DISPLAY INVISIBLE (-490 1360);
FORCEPROP 1 LASTPIN (-500 1350) BN 7
J 0
(-512 1358);
DISPLAY 0.680851 (-512 1358);
PAINT GREEN (-512 1358);
FORCEPROP 2 LAST CDS_LIB standard
J 0
(-450 1350);
PAINT MONO (-450 1350);
DISPLAY INVISIBLE (-450 1350);
FORCEPROP 1 LAST BODY_TYPE PLUMBING
J 0
(-450 1400);
DISPLAY 0.872340 (-450 1400);
PAINT GREEN (-450 1400);
DISPLAY INVISIBLE (-450 1400);
FORCEPROP 1 LAST HDL_TAP TRUE
J 0
(-125 1225);
DISPLAY 0.872340 (-125 1225);
DISPLAY INVISIBLE (-125 1225);
FORCEPROP 1 LAST PATH I54
J 0
(-452 1350);
DISPLAY 0.872340 (-452 1350);
PAINT GREEN (-452 1350);
DISPLAY INVISIBLE (-452 1350);
FORCEADD TAP..1
(-450 1400);
FORCEPROP 3 LASTPIN (-500 1400) SIG_NAME M_C_CPU0_SB_DQ<8>
J 0
(-490 1410);
DISPLAY 0.659574 (-490 1410);
PAINT MONO (-490 1410);
DISPLAY INVISIBLE (-490 1410);
FORCEPROP 1 LASTPIN (-500 1400) BN 8
J 0
(-512 1408);
DISPLAY 0.680851 (-512 1408);
PAINT GREEN (-512 1408);
FORCEPROP 2 LAST CDS_LIB standard
J 0
(-450 1400);
PAINT MONO (-450 1400);
DISPLAY INVISIBLE (-450 1400);
FORCEPROP 1 LAST BODY_TYPE PLUMBING
J 0
(-450 1450);
DISPLAY 0.872340 (-450 1450);
PAINT GREEN (-450 1450);
DISPLAY INVISIBLE (-450 1450);
FORCEPROP 1 LAST HDL_TAP TRUE
J 0
(-125 1275);
DISPLAY 0.872340 (-125 1275);
DISPLAY INVISIBLE (-125 1275);
FORCEPROP 1 LAST PATH I55
J 0
(-452 1400);
DISPLAY 0.872340 (-452 1400);
PAINT GREEN (-452 1400);
DISPLAY INVISIBLE (-452 1400);
FORCEADD TAP..1
(-450 1450);
FORCEPROP 3 LASTPIN (-500 1450) SIG_NAME M_C_CPU0_SB_DQ<9>
J 0
(-490 1460);
DISPLAY 0.659574 (-490 1460);
PAINT MONO (-490 1460);
DISPLAY INVISIBLE (-490 1460);
FORCEPROP 1 LASTPIN (-500 1450) BN 9
J 0
(-512 1458);
DISPLAY 0.680851 (-512 1458);
PAINT GREEN (-512 1458);
FORCEPROP 2 LAST CDS_LIB standard
J 0
(-450 1450);
PAINT MONO (-450 1450);
DISPLAY INVISIBLE (-450 1450);
FORCEPROP 1 LAST BODY_TYPE PLUMBING
J 0
(-450 1500);
DISPLAY 0.872340 (-450 1500);
PAINT GREEN (-450 1500);
DISPLAY INVISIBLE (-450 1500);
FORCEPROP 1 LAST HDL_TAP TRUE
J 0
(-125 1325);
DISPLAY 0.872340 (-125 1325);
DISPLAY INVISIBLE (-125 1325);
FORCEPROP 1 LAST PATH I56
J 0
(-452 1450);
DISPLAY 0.872340 (-452 1450);
PAINT GREEN (-452 1450);
DISPLAY INVISIBLE (-452 1450);
FORCEADD TAP..1
(-450 1550);
FORCEPROP 3 LASTPIN (-500 1550) SIG_NAME M_C_CPU0_SB_DQ<11>
J 0
(-490 1560);
DISPLAY 0.659574 (-490 1560);
PAINT MONO (-490 1560);
DISPLAY INVISIBLE (-490 1560);
FORCEPROP 1 LASTPIN (-500 1550) BN 11
J 0
(-512 1558);
DISPLAY 0.680851 (-512 1558);
PAINT GREEN (-512 1558);
FORCEPROP 2 LAST CDS_LIB standard
J 0
(-450 1550);
PAINT MONO (-450 1550);
DISPLAY INVISIBLE (-450 1550);
FORCEPROP 1 LAST BODY_TYPE PLUMBING
J 0
(-450 1600);
DISPLAY 0.872340 (-450 1600);
PAINT GREEN (-450 1600);
DISPLAY INVISIBLE (-450 1600);
FORCEPROP 1 LAST HDL_TAP TRUE
J 0
(-125 1425);
DISPLAY 0.872340 (-125 1425);
DISPLAY INVISIBLE (-125 1425);
FORCEPROP 1 LAST PATH I57
J 0
(-452 1550);
DISPLAY 0.872340 (-452 1550);
PAINT GREEN (-452 1550);
DISPLAY INVISIBLE (-452 1550);
FORCEADD TAP..1
(-450 1500);
FORCEPROP 3 LASTPIN (-500 1500) SIG_NAME M_C_CPU0_SB_DQ<10>
J 0
(-490 1510);
DISPLAY 0.659574 (-490 1510);
PAINT MONO (-490 1510);
DISPLAY INVISIBLE (-490 1510);
FORCEPROP 1 LASTPIN (-500 1500) BN 10
J 0
(-512 1508);
DISPLAY 0.680851 (-512 1508);
PAINT GREEN (-512 1508);
FORCEPROP 2 LAST CDS_LIB standard
J 0
(-450 1500);
PAINT MONO (-450 1500);
DISPLAY INVISIBLE (-450 1500);
FORCEPROP 1 LAST BODY_TYPE PLUMBING
J 0
(-450 1550);
DISPLAY 0.872340 (-450 1550);
PAINT GREEN (-450 1550);
DISPLAY INVISIBLE (-450 1550);
FORCEPROP 1 LAST HDL_TAP TRUE
J 0
(-125 1375);
DISPLAY 0.872340 (-125 1375);
DISPLAY INVISIBLE (-125 1375);
FORCEPROP 1 LAST PATH I58
J 0
(-452 1500);
DISPLAY 0.872340 (-452 1500);
PAINT GREEN (-452 1500);
DISPLAY INVISIBLE (-452 1500);
FORCEADD TAP..1
(-450 1600);
FORCEPROP 3 LASTPIN (-500 1600) SIG_NAME M_C_CPU0_SB_DQ<12>
J 0
(-490 1610);
DISPLAY 0.659574 (-490 1610);
PAINT MONO (-490 1610);
DISPLAY INVISIBLE (-490 1610);
FORCEPROP 1 LASTPIN (-500 1600) BN 12
J 0
(-512 1608);
DISPLAY 0.680851 (-512 1608);
PAINT GREEN (-512 1608);
FORCEPROP 2 LAST CDS_LIB standard
J 0
(-450 1600);
PAINT MONO (-450 1600);
DISPLAY INVISIBLE (-450 1600);
FORCEPROP 1 LAST BODY_TYPE PLUMBING
J 0
(-450 1650);
DISPLAY 0.872340 (-450 1650);
PAINT GREEN (-450 1650);
DISPLAY INVISIBLE (-450 1650);
FORCEPROP 1 LAST HDL_TAP TRUE
J 0
(-125 1475);
DISPLAY 0.872340 (-125 1475);
DISPLAY INVISIBLE (-125 1475);
FORCEPROP 1 LAST PATH I59
J 0
(-452 1600);
DISPLAY 0.872340 (-452 1600);
PAINT GREEN (-452 1600);
DISPLAY INVISIBLE (-452 1600);
FORCEADD OFFPAGE..1
(-2950 1700);
FORCEPROP 2 LAST $XR0 87 
J 0
(-3201 1700);
DISPLAY 0.638298 (-3201 1700);
PAINT MONO (-3201 1700);
FORCEPROP 2 LAST CDS_LIB standard
J 0
(-2950 1700);
PAINT MONO (-2950 1700);
DISPLAY INVISIBLE (-2950 1700);
FORCEPROP 1 LAST OFFPAGE TRUE
J 0
(-2625 1575);
DISPLAY 0.872340 (-2625 1575);
DISPLAY INVISIBLE (-2625 1575);
FORCEPROP 1 LAST COMMENT_BODY TRUE
J 0
(-2825 1600);
DISPLAY 0.872340 (-2825 1600);
PAINT GREEN (-2825 1600);
DISPLAY INVISIBLE (-2825 1600);
FORCEPROP 2 LAST PATH I6
J 0
(-2900 1775);
DISPLAY 1.021277 (-2900 1775);
DISPLAY INVISIBLE (-2900 1775);
FORCEADD TAP..1
(-450 1650);
FORCEPROP 3 LASTPIN (-500 1650) SIG_NAME M_C_CPU0_SB_DQ<13>
J 0
(-490 1660);
DISPLAY 0.659574 (-490 1660);
PAINT MONO (-490 1660);
DISPLAY INVISIBLE (-490 1660);
FORCEPROP 1 LASTPIN (-500 1650) BN 13
J 0
(-512 1658);
DISPLAY 0.680851 (-512 1658);
PAINT GREEN (-512 1658);
FORCEPROP 2 LAST CDS_LIB standard
J 0
(-450 1650);
PAINT MONO (-450 1650);
DISPLAY INVISIBLE (-450 1650);
FORCEPROP 1 LAST BODY_TYPE PLUMBING
J 0
(-450 1700);
DISPLAY 0.872340 (-450 1700);
PAINT GREEN (-450 1700);
DISPLAY INVISIBLE (-450 1700);
FORCEPROP 1 LAST HDL_TAP TRUE
J 0
(-125 1525);
DISPLAY 0.872340 (-125 1525);
DISPLAY INVISIBLE (-125 1525);
FORCEPROP 1 LAST PATH I60
J 0
(-452 1650);
DISPLAY 0.872340 (-452 1650);
PAINT GREEN (-452 1650);
DISPLAY INVISIBLE (-452 1650);
FORCEADD TAP..1
(-450 1700);
FORCEPROP 3 LASTPIN (-500 1700) SIG_NAME M_C_CPU0_SB_DQ<14>
J 0
(-490 1710);
DISPLAY 0.659574 (-490 1710);
PAINT MONO (-490 1710);
DISPLAY INVISIBLE (-490 1710);
FORCEPROP 1 LASTPIN (-500 1700) BN 14
J 0
(-512 1708);
DISPLAY 0.680851 (-512 1708);
PAINT GREEN (-512 1708);
FORCEPROP 2 LAST CDS_LIB standard
J 0
(-450 1700);
PAINT MONO (-450 1700);
DISPLAY INVISIBLE (-450 1700);
FORCEPROP 1 LAST BODY_TYPE PLUMBING
J 0
(-450 1750);
DISPLAY 0.872340 (-450 1750);
PAINT GREEN (-450 1750);
DISPLAY INVISIBLE (-450 1750);
FORCEPROP 1 LAST HDL_TAP TRUE
J 0
(-125 1575);
DISPLAY 0.872340 (-125 1575);
DISPLAY INVISIBLE (-125 1575);
FORCEPROP 1 LAST PATH I61
J 0
(-452 1700);
DISPLAY 0.872340 (-452 1700);
PAINT GREEN (-452 1700);
DISPLAY INVISIBLE (-452 1700);
FORCEADD TAP..1
(-450 1800);
FORCEPROP 3 LASTPIN (-500 1800) SIG_NAME M_C_CPU0_SB_DQ<16>
J 0
(-490 1810);
DISPLAY 0.659574 (-490 1810);
PAINT MONO (-490 1810);
DISPLAY INVISIBLE (-490 1810);
FORCEPROP 1 LASTPIN (-500 1800) BN 16
J 0
(-512 1808);
DISPLAY 0.680851 (-512 1808);
PAINT GREEN (-512 1808);
FORCEPROP 2 LAST CDS_LIB standard
J 0
(-450 1800);
PAINT MONO (-450 1800);
DISPLAY INVISIBLE (-450 1800);
FORCEPROP 1 LAST BODY_TYPE PLUMBING
J 0
(-450 1850);
DISPLAY 0.872340 (-450 1850);
PAINT GREEN (-450 1850);
DISPLAY INVISIBLE (-450 1850);
FORCEPROP 1 LAST HDL_TAP TRUE
J 0
(-125 1675);
DISPLAY 0.872340 (-125 1675);
DISPLAY INVISIBLE (-125 1675);
FORCEPROP 1 LAST PATH I62
J 0
(-452 1800);
DISPLAY 0.872340 (-452 1800);
PAINT GREEN (-452 1800);
DISPLAY INVISIBLE (-452 1800);
FORCEADD TAP..1
(-450 1750);
FORCEPROP 3 LASTPIN (-500 1750) SIG_NAME M_C_CPU0_SB_DQ<15>
J 0
(-490 1760);
DISPLAY 0.659574 (-490 1760);
PAINT MONO (-490 1760);
DISPLAY INVISIBLE (-490 1760);
FORCEPROP 1 LASTPIN (-500 1750) BN 15
J 0
(-512 1758);
DISPLAY 0.680851 (-512 1758);
PAINT GREEN (-512 1758);
FORCEPROP 2 LAST CDS_LIB standard
J 0
(-450 1750);
PAINT MONO (-450 1750);
DISPLAY INVISIBLE (-450 1750);
FORCEPROP 1 LAST BODY_TYPE PLUMBING
J 0
(-450 1800);
DISPLAY 0.872340 (-450 1800);
PAINT GREEN (-450 1800);
DISPLAY INVISIBLE (-450 1800);
FORCEPROP 1 LAST HDL_TAP TRUE
J 0
(-125 1625);
DISPLAY 0.872340 (-125 1625);
DISPLAY INVISIBLE (-125 1625);
FORCEPROP 1 LAST PATH I63
J 0
(-452 1750);
DISPLAY 0.872340 (-452 1750);
PAINT GREEN (-452 1750);
DISPLAY INVISIBLE (-452 1750);
FORCEADD TAP..1
(-450 1900);
FORCEPROP 3 LASTPIN (-500 1900) SIG_NAME M_C_CPU0_SB_DQ<18>
J 0
(-490 1910);
DISPLAY 0.659574 (-490 1910);
PAINT MONO (-490 1910);
DISPLAY INVISIBLE (-490 1910);
FORCEPROP 1 LASTPIN (-500 1900) BN 18
J 0
(-512 1908);
DISPLAY 0.680851 (-512 1908);
PAINT GREEN (-512 1908);
FORCEPROP 2 LAST CDS_LIB standard
J 0
(-450 1900);
PAINT MONO (-450 1900);
DISPLAY INVISIBLE (-450 1900);
FORCEPROP 1 LAST BODY_TYPE PLUMBING
J 0
(-450 1950);
DISPLAY 0.872340 (-450 1950);
PAINT GREEN (-450 1950);
DISPLAY INVISIBLE (-450 1950);
FORCEPROP 1 LAST HDL_TAP TRUE
J 0
(-125 1775);
DISPLAY 0.872340 (-125 1775);
DISPLAY INVISIBLE (-125 1775);
FORCEPROP 1 LAST PATH I64
J 0
(-452 1900);
DISPLAY 0.872340 (-452 1900);
PAINT GREEN (-452 1900);
DISPLAY INVISIBLE (-452 1900);
FORCEADD TAP..1
(-450 1850);
FORCEPROP 3 LASTPIN (-500 1850) SIG_NAME M_C_CPU0_SB_DQ<17>
J 0
(-490 1860);
DISPLAY 0.659574 (-490 1860);
PAINT MONO (-490 1860);
DISPLAY INVISIBLE (-490 1860);
FORCEPROP 1 LASTPIN (-500 1850) BN 17
J 0
(-512 1858);
DISPLAY 0.680851 (-512 1858);
PAINT GREEN (-512 1858);
FORCEPROP 2 LAST CDS_LIB standard
J 0
(-450 1850);
PAINT MONO (-450 1850);
DISPLAY INVISIBLE (-450 1850);
FORCEPROP 1 LAST BODY_TYPE PLUMBING
J 0
(-450 1900);
DISPLAY 0.872340 (-450 1900);
PAINT GREEN (-450 1900);
DISPLAY INVISIBLE (-450 1900);
FORCEPROP 1 LAST HDL_TAP TRUE
J 0
(-125 1725);
DISPLAY 0.872340 (-125 1725);
DISPLAY INVISIBLE (-125 1725);
FORCEPROP 1 LAST PATH I65
J 0
(-452 1850);
DISPLAY 0.872340 (-452 1850);
PAINT GREEN (-452 1850);
DISPLAY INVISIBLE (-452 1850);
FORCEADD TAP..1
(-450 1950);
FORCEPROP 3 LASTPIN (-500 1950) SIG_NAME M_C_CPU0_SB_DQ<19>
J 0
(-490 1960);
DISPLAY 0.659574 (-490 1960);
PAINT MONO (-490 1960);
DISPLAY INVISIBLE (-490 1960);
FORCEPROP 1 LASTPIN (-500 1950) BN 19
J 0
(-512 1958);
DISPLAY 0.680851 (-512 1958);
PAINT GREEN (-512 1958);
FORCEPROP 2 LAST CDS_LIB standard
J 0
(-450 1950);
PAINT MONO (-450 1950);
DISPLAY INVISIBLE (-450 1950);
FORCEPROP 1 LAST BODY_TYPE PLUMBING
J 0
(-450 2000);
DISPLAY 0.872340 (-450 2000);
PAINT GREEN (-450 2000);
DISPLAY INVISIBLE (-450 2000);
FORCEPROP 1 LAST HDL_TAP TRUE
J 0
(-125 1825);
DISPLAY 0.872340 (-125 1825);
DISPLAY INVISIBLE (-125 1825);
FORCEPROP 1 LAST PATH I66
J 0
(-452 1950);
DISPLAY 0.872340 (-452 1950);
PAINT GREEN (-452 1950);
DISPLAY INVISIBLE (-452 1950);
FORCEADD TAP..1
(-450 2000);
FORCEPROP 3 LASTPIN (-500 2000) SIG_NAME M_C_CPU0_SB_DQ<20>
J 0
(-490 2010);
DISPLAY 0.659574 (-490 2010);
PAINT MONO (-490 2010);
DISPLAY INVISIBLE (-490 2010);
FORCEPROP 1 LASTPIN (-500 2000) BN 20
J 0
(-512 2008);
DISPLAY 0.680851 (-512 2008);
PAINT GREEN (-512 2008);
FORCEPROP 2 LAST CDS_LIB standard
J 0
(-450 2000);
PAINT MONO (-450 2000);
DISPLAY INVISIBLE (-450 2000);
FORCEPROP 1 LAST BODY_TYPE PLUMBING
J 0
(-450 2050);
DISPLAY 0.872340 (-450 2050);
PAINT GREEN (-450 2050);
DISPLAY INVISIBLE (-450 2050);
FORCEPROP 1 LAST HDL_TAP TRUE
J 0
(-125 1875);
DISPLAY 0.872340 (-125 1875);
DISPLAY INVISIBLE (-125 1875);
FORCEPROP 1 LAST PATH I67
J 0
(-452 2000);
DISPLAY 0.872340 (-452 2000);
PAINT GREEN (-452 2000);
DISPLAY INVISIBLE (-452 2000);
FORCEADD TAP..1
(-450 2100);
FORCEPROP 3 LASTPIN (-500 2100) SIG_NAME M_C_CPU0_SB_DQ<22>
J 0
(-490 2110);
DISPLAY 0.659574 (-490 2110);
PAINT MONO (-490 2110);
DISPLAY INVISIBLE (-490 2110);
FORCEPROP 1 LASTPIN (-500 2100) BN 22
J 0
(-512 2108);
DISPLAY 0.680851 (-512 2108);
PAINT GREEN (-512 2108);
FORCEPROP 2 LAST CDS_LIB standard
J 0
(-450 2100);
DISPLAY INVISIBLE (-450 2100);
FORCEPROP 1 LAST BODY_TYPE PLUMBING
J 0
(-450 2150);
DISPLAY 0.872340 (-450 2150);
PAINT GREEN (-450 2150);
DISPLAY INVISIBLE (-450 2150);
FORCEPROP 1 LAST HDL_TAP TRUE
J 0
(-125 1975);
DISPLAY 0.872340 (-125 1975);
DISPLAY INVISIBLE (-125 1975);
FORCEPROP 1 LAST PATH I68
J 0
(-452 2100);
DISPLAY 0.872340 (-452 2100);
PAINT GREEN (-452 2100);
DISPLAY INVISIBLE (-452 2100);
FORCEADD TAP..1
(-450 2050);
FORCEPROP 3 LASTPIN (-500 2050) SIG_NAME M_C_CPU0_SB_DQ<21>
J 0
(-490 2060);
DISPLAY 0.659574 (-490 2060);
PAINT MONO (-490 2060);
DISPLAY INVISIBLE (-490 2060);
FORCEPROP 1 LASTPIN (-500 2050) BN 21
J 0
(-512 2058);
DISPLAY 0.680851 (-512 2058);
PAINT GREEN (-512 2058);
FORCEPROP 2 LAST CDS_LIB standard
J 0
(-450 2050);
PAINT MONO (-450 2050);
DISPLAY INVISIBLE (-450 2050);
FORCEPROP 1 LAST BODY_TYPE PLUMBING
J 0
(-450 2100);
DISPLAY 0.872340 (-450 2100);
PAINT GREEN (-450 2100);
DISPLAY INVISIBLE (-450 2100);
FORCEPROP 1 LAST HDL_TAP TRUE
J 0
(-125 1925);
DISPLAY 0.872340 (-125 1925);
DISPLAY INVISIBLE (-125 1925);
FORCEPROP 1 LAST PATH I69
J 0
(-452 2050);
DISPLAY 0.872340 (-452 2050);
PAINT GREEN (-452 2050);
DISPLAY INVISIBLE (-452 2050);
FORCEADD OFFPAGE..1
(-3025 1850);
FORCEPROP 2 LAST $XR1 86 
J 0
(-3336 1850);
DISPLAY 0.638298 (-3336 1850);
PAINT MONO (-3336 1850);
FORCEPROP 2 LAST $XR0 22 
J 0
(-3246 1850);
DISPLAY 0.638298 (-3246 1850);
PAINT MONO (-3246 1850);
FORCEPROP 2 LAST CDS_LIB standard
J 0
(-3025 1850);
PAINT MONO (-3025 1850);
DISPLAY INVISIBLE (-3025 1850);
FORCEPROP 1 LAST OFFPAGE TRUE
J 0
(-2700 1725);
DISPLAY 0.872340 (-2700 1725);
DISPLAY INVISIBLE (-2700 1725);
FORCEPROP 1 LAST COMMENT_BODY TRUE
J 0
(-2900 1750);
DISPLAY 0.872340 (-2900 1750);
PAINT GREEN (-2900 1750);
DISPLAY INVISIBLE (-2900 1750);
FORCEPROP 2 LAST PATH I7
J 0
(-2975 1925);
DISPLAY 1.021277 (-2975 1925);
DISPLAY INVISIBLE (-2975 1925);
FORCEADD TAP..1
(-450 2150);
FORCEPROP 3 LASTPIN (-500 2150) SIG_NAME M_C_CPU0_SB_DQ<23>
J 0
(-490 2160);
DISPLAY 0.659574 (-490 2160);
PAINT MONO (-490 2160);
DISPLAY INVISIBLE (-490 2160);
FORCEPROP 1 LASTPIN (-500 2150) BN 23
J 0
(-512 2158);
DISPLAY 0.680851 (-512 2158);
PAINT GREEN (-512 2158);
FORCEPROP 2 LAST CDS_LIB standard
J 0
(-450 2150);
DISPLAY INVISIBLE (-450 2150);
FORCEPROP 1 LAST BODY_TYPE PLUMBING
J 0
(-450 2200);
DISPLAY 0.872340 (-450 2200);
PAINT GREEN (-450 2200);
DISPLAY INVISIBLE (-450 2200);
FORCEPROP 1 LAST HDL_TAP TRUE
J 0
(-125 2025);
DISPLAY 0.872340 (-125 2025);
DISPLAY INVISIBLE (-125 2025);
FORCEPROP 1 LAST PATH I70
J 0
(-452 2150);
DISPLAY 0.872340 (-452 2150);
PAINT GREEN (-452 2150);
DISPLAY INVISIBLE (-452 2150);
FORCEADD TAP..1
(-450 2200);
FORCEPROP 3 LASTPIN (-500 2200) SIG_NAME M_C_CPU0_SB_DQ<24>
J 0
(-490 2210);
DISPLAY 0.659574 (-490 2210);
PAINT MONO (-490 2210);
DISPLAY INVISIBLE (-490 2210);
FORCEPROP 1 LASTPIN (-500 2200) BN 24
J 0
(-512 2208);
DISPLAY 0.680851 (-512 2208);
PAINT GREEN (-512 2208);
FORCEPROP 2 LAST CDS_LIB standard
J 0
(-450 2200);
DISPLAY INVISIBLE (-450 2200);
FORCEPROP 1 LAST BODY_TYPE PLUMBING
J 0
(-450 2250);
DISPLAY 0.872340 (-450 2250);
PAINT GREEN (-450 2250);
DISPLAY INVISIBLE (-450 2250);
FORCEPROP 1 LAST HDL_TAP TRUE
J 0
(-125 2075);
DISPLAY 0.872340 (-125 2075);
DISPLAY INVISIBLE (-125 2075);
FORCEPROP 1 LAST PATH I71
J 0
(-452 2200);
DISPLAY 0.872340 (-452 2200);
PAINT GREEN (-452 2200);
DISPLAY INVISIBLE (-452 2200);
FORCEADD TAP..1
(-450 2250);
FORCEPROP 3 LASTPIN (-500 2250) SIG_NAME M_C_CPU0_SB_DQ<25>
J 0
(-490 2260);
DISPLAY 0.659574 (-490 2260);
PAINT MONO (-490 2260);
DISPLAY INVISIBLE (-490 2260);
FORCEPROP 1 LASTPIN (-500 2250) BN 25
J 0
(-512 2258);
DISPLAY 0.680851 (-512 2258);
PAINT GREEN (-512 2258);
FORCEPROP 2 LAST CDS_LIB standard
J 0
(-450 2250);
DISPLAY INVISIBLE (-450 2250);
FORCEPROP 1 LAST BODY_TYPE PLUMBING
J 0
(-450 2300);
DISPLAY 0.872340 (-450 2300);
PAINT GREEN (-450 2300);
DISPLAY INVISIBLE (-450 2300);
FORCEPROP 1 LAST HDL_TAP TRUE
J 0
(-125 2125);
DISPLAY 0.872340 (-125 2125);
DISPLAY INVISIBLE (-125 2125);
FORCEPROP 1 LAST PATH I72
J 0
(-452 2250);
DISPLAY 0.872340 (-452 2250);
PAINT GREEN (-452 2250);
DISPLAY INVISIBLE (-452 2250);
FORCEADD TAP..1
(-450 2350);
FORCEPROP 3 LASTPIN (-500 2350) SIG_NAME M_C_CPU0_SB_DQ<27>
J 0
(-490 2360);
DISPLAY 0.659574 (-490 2360);
PAINT MONO (-490 2360);
DISPLAY INVISIBLE (-490 2360);
FORCEPROP 1 LASTPIN (-500 2350) BN 27
J 0
(-512 2358);
DISPLAY 0.680851 (-512 2358);
PAINT GREEN (-512 2358);
FORCEPROP 2 LAST CDS_LIB standard
J 0
(-450 2350);
DISPLAY INVISIBLE (-450 2350);
FORCEPROP 1 LAST BODY_TYPE PLUMBING
J 0
(-450 2400);
DISPLAY 0.872340 (-450 2400);
PAINT GREEN (-450 2400);
DISPLAY INVISIBLE (-450 2400);
FORCEPROP 1 LAST HDL_TAP TRUE
J 0
(-125 2225);
DISPLAY 0.872340 (-125 2225);
DISPLAY INVISIBLE (-125 2225);
FORCEPROP 1 LAST PATH I73
J 0
(-452 2350);
DISPLAY 0.872340 (-452 2350);
PAINT GREEN (-452 2350);
DISPLAY INVISIBLE (-452 2350);
FORCEADD TAP..1
(-450 2300);
FORCEPROP 3 LASTPIN (-500 2300) SIG_NAME M_C_CPU0_SB_DQ<26>
J 0
(-490 2310);
DISPLAY 0.659574 (-490 2310);
PAINT MONO (-490 2310);
DISPLAY INVISIBLE (-490 2310);
FORCEPROP 1 LASTPIN (-500 2300) BN 26
J 0
(-512 2308);
DISPLAY 0.680851 (-512 2308);
PAINT GREEN (-512 2308);
FORCEPROP 2 LAST CDS_LIB standard
J 0
(-450 2300);
DISPLAY INVISIBLE (-450 2300);
FORCEPROP 1 LAST BODY_TYPE PLUMBING
J 0
(-450 2350);
DISPLAY 0.872340 (-450 2350);
PAINT GREEN (-450 2350);
DISPLAY INVISIBLE (-450 2350);
FORCEPROP 1 LAST HDL_TAP TRUE
J 0
(-125 2175);
DISPLAY 0.872340 (-125 2175);
DISPLAY INVISIBLE (-125 2175);
FORCEPROP 1 LAST PATH I74
J 0
(-452 2300);
DISPLAY 0.872340 (-452 2300);
PAINT GREEN (-452 2300);
DISPLAY INVISIBLE (-452 2300);
FORCEADD TAP..1
(-450 2400);
FORCEPROP 3 LASTPIN (-500 2400) SIG_NAME M_C_CPU0_SB_DQ<28>
J 0
(-490 2410);
DISPLAY 0.659574 (-490 2410);
PAINT MONO (-490 2410);
DISPLAY INVISIBLE (-490 2410);
FORCEPROP 1 LASTPIN (-500 2400) BN 28
J 0
(-512 2408);
DISPLAY 0.680851 (-512 2408);
PAINT GREEN (-512 2408);
FORCEPROP 2 LAST CDS_LIB standard
J 0
(-450 2400);
DISPLAY INVISIBLE (-450 2400);
FORCEPROP 1 LAST BODY_TYPE PLUMBING
J 0
(-450 2450);
DISPLAY 0.872340 (-450 2450);
PAINT GREEN (-450 2450);
DISPLAY INVISIBLE (-450 2450);
FORCEPROP 1 LAST HDL_TAP TRUE
J 0
(-125 2275);
DISPLAY 0.872340 (-125 2275);
DISPLAY INVISIBLE (-125 2275);
FORCEPROP 1 LAST PATH I75
J 0
(-452 2400);
DISPLAY 0.872340 (-452 2400);
PAINT GREEN (-452 2400);
DISPLAY INVISIBLE (-452 2400);
FORCEADD TAP..1
(-450 2450);
FORCEPROP 3 LASTPIN (-500 2450) SIG_NAME M_C_CPU0_SB_DQ<29>
J 0
(-490 2460);
DISPLAY 0.659574 (-490 2460);
PAINT MONO (-490 2460);
DISPLAY INVISIBLE (-490 2460);
FORCEPROP 1 LASTPIN (-500 2450) BN 29
J 0
(-512 2458);
DISPLAY 0.680851 (-512 2458);
PAINT GREEN (-512 2458);
FORCEPROP 2 LAST CDS_LIB standard
J 0
(-450 2450);
DISPLAY INVISIBLE (-450 2450);
FORCEPROP 1 LAST BODY_TYPE PLUMBING
J 0
(-450 2500);
DISPLAY 0.872340 (-450 2500);
PAINT GREEN (-450 2500);
DISPLAY INVISIBLE (-450 2500);
FORCEPROP 1 LAST HDL_TAP TRUE
J 0
(-125 2325);
DISPLAY 0.872340 (-125 2325);
DISPLAY INVISIBLE (-125 2325);
FORCEPROP 1 LAST PATH I76
J 0
(-452 2450);
DISPLAY 0.872340 (-452 2450);
PAINT GREEN (-452 2450);
DISPLAY INVISIBLE (-452 2450);
FORCEADD TAP..1
(-450 2500);
FORCEPROP 3 LASTPIN (-500 2500) SIG_NAME M_C_CPU0_SB_DQ<30>
J 0
(-490 2510);
DISPLAY 0.659574 (-490 2510);
PAINT MONO (-490 2510);
DISPLAY INVISIBLE (-490 2510);
FORCEPROP 1 LASTPIN (-500 2500) BN 30
J 0
(-512 2508);
DISPLAY 0.680851 (-512 2508);
PAINT GREEN (-512 2508);
FORCEPROP 2 LAST CDS_LIB standard
J 0
(-450 2500);
DISPLAY INVISIBLE (-450 2500);
FORCEPROP 1 LAST BODY_TYPE PLUMBING
J 0
(-450 2550);
DISPLAY 0.872340 (-450 2550);
PAINT GREEN (-450 2550);
DISPLAY INVISIBLE (-450 2550);
FORCEPROP 1 LAST HDL_TAP TRUE
J 0
(-125 2375);
DISPLAY 0.872340 (-125 2375);
DISPLAY INVISIBLE (-125 2375);
FORCEPROP 1 LAST PATH I77
J 0
(-452 2500);
DISPLAY 0.872340 (-452 2500);
PAINT GREEN (-452 2500);
DISPLAY INVISIBLE (-452 2500);
FORCEADD TAP..1
(-450 2550);
FORCEPROP 3 LASTPIN (-500 2550) SIG_NAME M_C_CPU0_SB_DQ<31>
J 0
(-490 2560);
DISPLAY 0.659574 (-490 2560);
PAINT MONO (-490 2560);
DISPLAY INVISIBLE (-490 2560);
FORCEPROP 1 LASTPIN (-500 2550) BN 31
J 0
(-512 2558);
DISPLAY 0.680851 (-512 2558);
PAINT GREEN (-512 2558);
FORCEPROP 2 LAST CDS_LIB standard
J 0
(-450 2550);
DISPLAY INVISIBLE (-450 2550);
FORCEPROP 1 LAST BODY_TYPE PLUMBING
J 0
(-450 2600);
DISPLAY 0.872340 (-450 2600);
PAINT GREEN (-450 2600);
DISPLAY INVISIBLE (-450 2600);
FORCEPROP 1 LAST HDL_TAP TRUE
J 0
(-125 2425);
DISPLAY 0.872340 (-125 2425);
DISPLAY INVISIBLE (-125 2425);
FORCEPROP 1 LAST PATH I78
J 0
(-452 2550);
DISPLAY 0.872340 (-452 2550);
PAINT GREEN (-452 2550);
DISPLAY INVISIBLE (-452 2550);
FORCEADD TAP..1
(-450 2650);
FORCEPROP 3 LASTPIN (-500 2650) SIG_NAME M_C_CPU0_SA_DQ<0>
J 0
(-490 2660);
DISPLAY 0.659574 (-490 2660);
PAINT MONO (-490 2660);
DISPLAY INVISIBLE (-490 2660);
FORCEPROP 1 LASTPIN (-500 2650) BN 0
J 0
(-512 2658);
DISPLAY 0.680851 (-512 2658);
PAINT GREEN (-512 2658);
FORCEPROP 2 LAST CDS_LIB standard
J 0
(-450 2650);
PAINT MONO (-450 2650);
DISPLAY INVISIBLE (-450 2650);
FORCEPROP 1 LAST BODY_TYPE PLUMBING
J 0
(-450 2700);
DISPLAY 0.872340 (-450 2700);
PAINT GREEN (-450 2700);
DISPLAY INVISIBLE (-450 2700);
FORCEPROP 1 LAST HDL_TAP TRUE
J 0
(-125 2525);
DISPLAY 0.872340 (-125 2525);
DISPLAY INVISIBLE (-125 2525);
FORCEPROP 1 LAST PATH I79
J 0
(-452 2650);
DISPLAY 0.872340 (-452 2650);
PAINT GREEN (-452 2650);
DISPLAY INVISIBLE (-452 2650);
FORCEADD OFFPAGE..1
(-3025 1950);
FORCEPROP 2 LAST $XR3 89 
J 0
(-3277 1914);
DISPLAY 0.638298 (-3277 1914);
PAINT MONO (-3277 1914);
FORCEPROP 2 LAST $XR2 88 
J 0
(-3457 1950);
DISPLAY 0.638298 (-3457 1950);
PAINT MONO (-3457 1950);
FORCEPROP 2 LAST $XR1 86 
J 0
(-3367 1950);
DISPLAY 0.638298 (-3367 1950);
PAINT MONO (-3367 1950);
FORCEPROP 2 LAST $XR0 129 
J 0
(-3277 1950);
DISPLAY 0.638298 (-3277 1950);
PAINT MONO (-3277 1950);
FORCEPROP 2 LAST CDS_LIB standard
J 0
(-3025 1950);
PAINT MONO (-3025 1950);
DISPLAY INVISIBLE (-3025 1950);
FORCEPROP 1 LAST OFFPAGE TRUE
J 0
(-2700 1825);
DISPLAY 0.872340 (-2700 1825);
DISPLAY INVISIBLE (-2700 1825);
FORCEPROP 1 LAST COMMENT_BODY TRUE
J 0
(-2900 1850);
DISPLAY 0.872340 (-2900 1850);
PAINT GREEN (-2900 1850);
DISPLAY INVISIBLE (-2900 1850);
FORCEPROP 2 LAST PATH I8
J 0
(-2975 2025);
DISPLAY 1.021277 (-2975 2025);
DISPLAY INVISIBLE (-2975 2025);
FORCEADD TAP..1
(-450 2700);
FORCEPROP 3 LASTPIN (-500 2700) SIG_NAME M_C_CPU0_SA_DQ<1>
J 0
(-490 2710);
DISPLAY 0.659574 (-490 2710);
PAINT MONO (-490 2710);
DISPLAY INVISIBLE (-490 2710);
FORCEPROP 1 LASTPIN (-500 2700) BN 1
J 0
(-512 2708);
DISPLAY 0.680851 (-512 2708);
PAINT GREEN (-512 2708);
FORCEPROP 2 LAST CDS_LIB standard
J 0
(-450 2700);
PAINT MONO (-450 2700);
DISPLAY INVISIBLE (-450 2700);
FORCEPROP 1 LAST BODY_TYPE PLUMBING
J 0
(-450 2750);
DISPLAY 0.872340 (-450 2750);
PAINT GREEN (-450 2750);
DISPLAY INVISIBLE (-450 2750);
FORCEPROP 1 LAST HDL_TAP TRUE
J 0
(-125 2575);
DISPLAY 0.872340 (-125 2575);
DISPLAY INVISIBLE (-125 2575);
FORCEPROP 1 LAST PATH I80
J 0
(-452 2700);
DISPLAY 0.872340 (-452 2700);
PAINT GREEN (-452 2700);
DISPLAY INVISIBLE (-452 2700);
FORCEADD TAP..1
(-450 2800);
FORCEPROP 3 LASTPIN (-500 2800) SIG_NAME M_C_CPU0_SA_DQ<3>
J 0
(-490 2810);
DISPLAY 0.659574 (-490 2810);
PAINT MONO (-490 2810);
DISPLAY INVISIBLE (-490 2810);
FORCEPROP 1 LASTPIN (-500 2800) BN 3
J 0
(-512 2808);
DISPLAY 0.680851 (-512 2808);
PAINT GREEN (-512 2808);
FORCEPROP 2 LAST CDS_LIB standard
J 0
(-450 2800);
PAINT MONO (-450 2800);
DISPLAY INVISIBLE (-450 2800);
FORCEPROP 1 LAST BODY_TYPE PLUMBING
J 0
(-450 2850);
DISPLAY 0.872340 (-450 2850);
PAINT GREEN (-450 2850);
DISPLAY INVISIBLE (-450 2850);
FORCEPROP 1 LAST HDL_TAP TRUE
J 0
(-125 2675);
DISPLAY 0.872340 (-125 2675);
DISPLAY INVISIBLE (-125 2675);
FORCEPROP 1 LAST PATH I81
J 0
(-452 2800);
DISPLAY 0.872340 (-452 2800);
PAINT GREEN (-452 2800);
DISPLAY INVISIBLE (-452 2800);
FORCEADD TAP..1
(-450 2750);
FORCEPROP 3 LASTPIN (-500 2750) SIG_NAME M_C_CPU0_SA_DQ<2>
J 0
(-490 2760);
DISPLAY 0.659574 (-490 2760);
PAINT MONO (-490 2760);
DISPLAY INVISIBLE (-490 2760);
FORCEPROP 1 LASTPIN (-500 2750) BN 2
J 0
(-512 2758);
DISPLAY 0.680851 (-512 2758);
PAINT GREEN (-512 2758);
FORCEPROP 2 LAST CDS_LIB standard
J 0
(-450 2750);
PAINT MONO (-450 2750);
DISPLAY INVISIBLE (-450 2750);
FORCEPROP 1 LAST BODY_TYPE PLUMBING
J 0
(-450 2800);
DISPLAY 0.872340 (-450 2800);
PAINT GREEN (-450 2800);
DISPLAY INVISIBLE (-450 2800);
FORCEPROP 1 LAST HDL_TAP TRUE
J 0
(-125 2625);
DISPLAY 0.872340 (-125 2625);
DISPLAY INVISIBLE (-125 2625);
FORCEPROP 1 LAST PATH I82
J 0
(-452 2750);
DISPLAY 0.872340 (-452 2750);
PAINT GREEN (-452 2750);
DISPLAY INVISIBLE (-452 2750);
FORCEADD TAP..1
(-450 2850);
FORCEPROP 3 LASTPIN (-500 2850) SIG_NAME M_C_CPU0_SA_DQ<4>
J 0
(-490 2860);
DISPLAY 0.659574 (-490 2860);
PAINT MONO (-490 2860);
DISPLAY INVISIBLE (-490 2860);
FORCEPROP 1 LASTPIN (-500 2850) BN 4
J 0
(-512 2858);
DISPLAY 0.680851 (-512 2858);
PAINT GREEN (-512 2858);
FORCEPROP 2 LAST CDS_LIB standard
J 0
(-450 2850);
PAINT MONO (-450 2850);
DISPLAY INVISIBLE (-450 2850);
FORCEPROP 1 LAST BODY_TYPE PLUMBING
J 0
(-450 2900);
DISPLAY 0.872340 (-450 2900);
PAINT GREEN (-450 2900);
DISPLAY INVISIBLE (-450 2900);
FORCEPROP 1 LAST HDL_TAP TRUE
J 0
(-125 2725);
DISPLAY 0.872340 (-125 2725);
DISPLAY INVISIBLE (-125 2725);
FORCEPROP 1 LAST PATH I83
J 0
(-452 2850);
DISPLAY 0.872340 (-452 2850);
PAINT GREEN (-452 2850);
DISPLAY INVISIBLE (-452 2850);
FORCEADD TAP..1
(-450 2900);
FORCEPROP 3 LASTPIN (-500 2900) SIG_NAME M_C_CPU0_SA_DQ<5>
J 0
(-490 2910);
DISPLAY 0.659574 (-490 2910);
PAINT MONO (-490 2910);
DISPLAY INVISIBLE (-490 2910);
FORCEPROP 1 LASTPIN (-500 2900) BN 5
J 0
(-512 2908);
DISPLAY 0.680851 (-512 2908);
PAINT GREEN (-512 2908);
FORCEPROP 2 LAST CDS_LIB standard
J 0
(-450 2900);
PAINT MONO (-450 2900);
DISPLAY INVISIBLE (-450 2900);
FORCEPROP 1 LAST BODY_TYPE PLUMBING
J 0
(-450 2950);
DISPLAY 0.872340 (-450 2950);
PAINT GREEN (-450 2950);
DISPLAY INVISIBLE (-450 2950);
FORCEPROP 1 LAST HDL_TAP TRUE
J 0
(-125 2775);
DISPLAY 0.872340 (-125 2775);
DISPLAY INVISIBLE (-125 2775);
FORCEPROP 1 LAST PATH I84
J 0
(-452 2900);
DISPLAY 0.872340 (-452 2900);
PAINT GREEN (-452 2900);
DISPLAY INVISIBLE (-452 2900);
FORCEADD TAP..1
(-450 2950);
FORCEPROP 3 LASTPIN (-500 2950) SIG_NAME M_C_CPU0_SA_DQ<6>
J 0
(-490 2960);
DISPLAY 0.659574 (-490 2960);
PAINT MONO (-490 2960);
DISPLAY INVISIBLE (-490 2960);
FORCEPROP 1 LASTPIN (-500 2950) BN 6
J 0
(-512 2958);
DISPLAY 0.680851 (-512 2958);
PAINT GREEN (-512 2958);
FORCEPROP 2 LAST CDS_LIB standard
J 0
(-450 2950);
PAINT MONO (-450 2950);
DISPLAY INVISIBLE (-450 2950);
FORCEPROP 1 LAST BODY_TYPE PLUMBING
J 0
(-450 3000);
DISPLAY 0.872340 (-450 3000);
PAINT GREEN (-450 3000);
DISPLAY INVISIBLE (-450 3000);
FORCEPROP 1 LAST HDL_TAP TRUE
J 0
(-125 2825);
DISPLAY 0.872340 (-125 2825);
DISPLAY INVISIBLE (-125 2825);
FORCEPROP 1 LAST PATH I85
J 0
(-452 2950);
DISPLAY 0.872340 (-452 2950);
PAINT GREEN (-452 2950);
DISPLAY INVISIBLE (-452 2950);
FORCEADD TAP..1
(-450 3000);
FORCEPROP 3 LASTPIN (-500 3000) SIG_NAME M_C_CPU0_SA_DQ<7>
J 0
(-490 3010);
DISPLAY 0.659574 (-490 3010);
PAINT MONO (-490 3010);
DISPLAY INVISIBLE (-490 3010);
FORCEPROP 1 LASTPIN (-500 3000) BN 7
J 0
(-512 3008);
DISPLAY 0.680851 (-512 3008);
PAINT GREEN (-512 3008);
FORCEPROP 2 LAST CDS_LIB standard
J 0
(-450 3000);
PAINT MONO (-450 3000);
DISPLAY INVISIBLE (-450 3000);
FORCEPROP 1 LAST BODY_TYPE PLUMBING
J 0
(-450 3050);
DISPLAY 0.872340 (-450 3050);
PAINT GREEN (-450 3050);
DISPLAY INVISIBLE (-450 3050);
FORCEPROP 1 LAST HDL_TAP TRUE
J 0
(-125 2875);
DISPLAY 0.872340 (-125 2875);
DISPLAY INVISIBLE (-125 2875);
FORCEPROP 1 LAST PATH I86
J 0
(-452 3000);
DISPLAY 0.872340 (-452 3000);
PAINT GREEN (-452 3000);
DISPLAY INVISIBLE (-452 3000);
FORCEADD TAP..1
(-450 3100);
FORCEPROP 3 LASTPIN (-500 3100) SIG_NAME M_C_CPU0_SA_DQ<9>
J 0
(-490 3110);
DISPLAY 0.659574 (-490 3110);
PAINT MONO (-490 3110);
DISPLAY INVISIBLE (-490 3110);
FORCEPROP 1 LASTPIN (-500 3100) BN 9
J 0
(-512 3108);
DISPLAY 0.680851 (-512 3108);
PAINT GREEN (-512 3108);
FORCEPROP 2 LAST CDS_LIB standard
J 0
(-450 3100);
PAINT MONO (-450 3100);
DISPLAY INVISIBLE (-450 3100);
FORCEPROP 1 LAST BODY_TYPE PLUMBING
J 0
(-450 3150);
DISPLAY 0.872340 (-450 3150);
PAINT GREEN (-450 3150);
DISPLAY INVISIBLE (-450 3150);
FORCEPROP 1 LAST HDL_TAP TRUE
J 0
(-125 2975);
DISPLAY 0.872340 (-125 2975);
DISPLAY INVISIBLE (-125 2975);
FORCEPROP 1 LAST PATH I87
J 0
(-452 3100);
DISPLAY 0.872340 (-452 3100);
PAINT GREEN (-452 3100);
DISPLAY INVISIBLE (-452 3100);
FORCEADD TAP..1
(-450 3050);
FORCEPROP 3 LASTPIN (-500 3050) SIG_NAME M_C_CPU0_SA_DQ<8>
J 0
(-490 3060);
DISPLAY 0.659574 (-490 3060);
PAINT MONO (-490 3060);
DISPLAY INVISIBLE (-490 3060);
FORCEPROP 1 LASTPIN (-500 3050) BN 8
J 0
(-512 3058);
DISPLAY 0.680851 (-512 3058);
PAINT GREEN (-512 3058);
FORCEPROP 2 LAST CDS_LIB standard
J 0
(-450 3050);
PAINT MONO (-450 3050);
DISPLAY INVISIBLE (-450 3050);
FORCEPROP 1 LAST BODY_TYPE PLUMBING
J 0
(-450 3100);
DISPLAY 0.872340 (-450 3100);
PAINT GREEN (-450 3100);
DISPLAY INVISIBLE (-450 3100);
FORCEPROP 1 LAST HDL_TAP TRUE
J 0
(-125 2925);
DISPLAY 0.872340 (-125 2925);
DISPLAY INVISIBLE (-125 2925);
FORCEPROP 1 LAST PATH I88
J 0
(-452 3050);
DISPLAY 0.872340 (-452 3050);
PAINT GREEN (-452 3050);
DISPLAY INVISIBLE (-452 3050);
FORCEADD TAP..1
(-450 3150);
FORCEPROP 3 LASTPIN (-500 3150) SIG_NAME M_C_CPU0_SA_DQ<10>
J 0
(-490 3160);
DISPLAY 0.659574 (-490 3160);
PAINT MONO (-490 3160);
DISPLAY INVISIBLE (-490 3160);
FORCEPROP 1 LASTPIN (-500 3150) BN 10
J 0
(-512 3158);
DISPLAY 0.680851 (-512 3158);
PAINT GREEN (-512 3158);
FORCEPROP 2 LAST CDS_LIB standard
J 0
(-450 3150);
PAINT MONO (-450 3150);
DISPLAY INVISIBLE (-450 3150);
FORCEPROP 1 LAST BODY_TYPE PLUMBING
J 0
(-450 3200);
DISPLAY 0.872340 (-450 3200);
PAINT GREEN (-450 3200);
DISPLAY INVISIBLE (-450 3200);
FORCEPROP 1 LAST HDL_TAP TRUE
J 0
(-125 3025);
DISPLAY 0.872340 (-125 3025);
DISPLAY INVISIBLE (-125 3025);
FORCEPROP 1 LAST PATH I89
J 0
(-452 3150);
DISPLAY 0.872340 (-452 3150);
PAINT GREEN (-452 3150);
DISPLAY INVISIBLE (-452 3150);
FORCEADD OFFPAGE..3
R 2
(-3025 2375);
FORCEPROP 2 LAST $XR1 86 
J 0
(-3364 2375);
DISPLAY 0.638298 (-3364 2375);
PAINT MONO (-3364 2375);
FORCEPROP 2 LAST $XR0 22 
J 0
(-3274 2375);
DISPLAY 0.638298 (-3274 2375);
PAINT MONO (-3274 2375);
FORCEPROP 2 LAST CDS_LIB standard
J 0
(-3025 2375);
PAINT MONO (-3025 2375);
DISPLAY INVISIBLE (-3025 2375);
FORCEPROP 1 LAST OFFPAGE TRUE
J 2
(-3350 2250);
DISPLAY 0.872340 (-3350 2250);
DISPLAY INVISIBLE (-3350 2250);
FORCEPROP 1 LAST COMMENT_BODY TRUE
J 2
(-2975 2275);
DISPLAY 0.872340 (-2975 2275);
PAINT GREEN (-2975 2275);
DISPLAY INVISIBLE (-2975 2275);
FORCEPROP 2 LAST PATH I9
J 0
(-2975 2450);
DISPLAY 1.021277 (-2975 2450);
DISPLAY INVISIBLE (-2975 2450);
FORCEADD TAP..1
(-450 3250);
FORCEPROP 3 LASTPIN (-500 3250) SIG_NAME M_C_CPU0_SA_DQ<12>
J 0
(-490 3260);
DISPLAY 0.659574 (-490 3260);
PAINT MONO (-490 3260);
DISPLAY INVISIBLE (-490 3260);
FORCEPROP 1 LASTPIN (-500 3250) BN 12
J 0
(-512 3258);
DISPLAY 0.680851 (-512 3258);
PAINT GREEN (-512 3258);
FORCEPROP 2 LAST CDS_LIB standard
J 0
(-450 3250);
PAINT MONO (-450 3250);
DISPLAY INVISIBLE (-450 3250);
FORCEPROP 1 LAST BODY_TYPE PLUMBING
J 0
(-450 3300);
DISPLAY 0.872340 (-450 3300);
PAINT GREEN (-450 3300);
DISPLAY INVISIBLE (-450 3300);
FORCEPROP 1 LAST HDL_TAP TRUE
J 0
(-125 3125);
DISPLAY 0.872340 (-125 3125);
DISPLAY INVISIBLE (-125 3125);
FORCEPROP 1 LAST PATH I90
J 0
(-452 3250);
DISPLAY 0.872340 (-452 3250);
PAINT GREEN (-452 3250);
DISPLAY INVISIBLE (-452 3250);
FORCEADD TAP..1
(-450 3200);
FORCEPROP 3 LASTPIN (-500 3200) SIG_NAME M_C_CPU0_SA_DQ<11>
J 0
(-490 3210);
DISPLAY 0.659574 (-490 3210);
PAINT MONO (-490 3210);
DISPLAY INVISIBLE (-490 3210);
FORCEPROP 1 LASTPIN (-500 3200) BN 11
J 0
(-512 3208);
DISPLAY 0.680851 (-512 3208);
PAINT GREEN (-512 3208);
FORCEPROP 2 LAST CDS_LIB standard
J 0
(-450 3200);
PAINT MONO (-450 3200);
DISPLAY INVISIBLE (-450 3200);
FORCEPROP 1 LAST BODY_TYPE PLUMBING
J 0
(-450 3250);
DISPLAY 0.872340 (-450 3250);
PAINT GREEN (-450 3250);
DISPLAY INVISIBLE (-450 3250);
FORCEPROP 1 LAST HDL_TAP TRUE
J 0
(-125 3075);
DISPLAY 0.872340 (-125 3075);
DISPLAY INVISIBLE (-125 3075);
FORCEPROP 1 LAST PATH I91
J 0
(-452 3200);
DISPLAY 0.872340 (-452 3200);
PAINT GREEN (-452 3200);
DISPLAY INVISIBLE (-452 3200);
FORCEADD TAP..1
(-450 3350);
FORCEPROP 3 LASTPIN (-500 3350) SIG_NAME M_C_CPU0_SA_DQ<14>
J 0
(-490 3360);
DISPLAY 0.659574 (-490 3360);
PAINT MONO (-490 3360);
DISPLAY INVISIBLE (-490 3360);
FORCEPROP 1 LASTPIN (-500 3350) BN 14
J 0
(-512 3358);
DISPLAY 0.680851 (-512 3358);
PAINT GREEN (-512 3358);
FORCEPROP 2 LAST CDS_LIB standard
J 0
(-450 3350);
PAINT MONO (-450 3350);
DISPLAY INVISIBLE (-450 3350);
FORCEPROP 1 LAST BODY_TYPE PLUMBING
J 0
(-450 3400);
DISPLAY 0.872340 (-450 3400);
PAINT GREEN (-450 3400);
DISPLAY INVISIBLE (-450 3400);
FORCEPROP 1 LAST HDL_TAP TRUE
J 0
(-125 3225);
DISPLAY 0.872340 (-125 3225);
DISPLAY INVISIBLE (-125 3225);
FORCEPROP 1 LAST PATH I92
J 0
(-452 3350);
DISPLAY 0.872340 (-452 3350);
PAINT GREEN (-452 3350);
DISPLAY INVISIBLE (-452 3350);
FORCEADD TAP..1
(-450 3300);
FORCEPROP 3 LASTPIN (-500 3300) SIG_NAME M_C_CPU0_SA_DQ<13>
J 0
(-490 3310);
DISPLAY 0.659574 (-490 3310);
PAINT MONO (-490 3310);
DISPLAY INVISIBLE (-490 3310);
FORCEPROP 1 LASTPIN (-500 3300) BN 13
J 0
(-512 3308);
DISPLAY 0.680851 (-512 3308);
PAINT GREEN (-512 3308);
FORCEPROP 2 LAST CDS_LIB standard
J 0
(-450 3300);
PAINT MONO (-450 3300);
DISPLAY INVISIBLE (-450 3300);
FORCEPROP 1 LAST BODY_TYPE PLUMBING
J 0
(-450 3350);
DISPLAY 0.872340 (-450 3350);
PAINT GREEN (-450 3350);
DISPLAY INVISIBLE (-450 3350);
FORCEPROP 1 LAST HDL_TAP TRUE
J 0
(-125 3175);
DISPLAY 0.872340 (-125 3175);
DISPLAY INVISIBLE (-125 3175);
FORCEPROP 1 LAST PATH I93
J 0
(-452 3300);
DISPLAY 0.872340 (-452 3300);
PAINT GREEN (-452 3300);
DISPLAY INVISIBLE (-452 3300);
FORCEADD TAP..1
(-450 3400);
FORCEPROP 3 LASTPIN (-500 3400) SIG_NAME M_C_CPU0_SA_DQ<15>
J 0
(-490 3410);
DISPLAY 0.659574 (-490 3410);
PAINT MONO (-490 3410);
DISPLAY INVISIBLE (-490 3410);
FORCEPROP 1 LASTPIN (-500 3400) BN 15
J 0
(-512 3408);
DISPLAY 0.680851 (-512 3408);
PAINT GREEN (-512 3408);
FORCEPROP 2 LAST CDS_LIB standard
J 0
(-450 3400);
PAINT MONO (-450 3400);
DISPLAY INVISIBLE (-450 3400);
FORCEPROP 1 LAST BODY_TYPE PLUMBING
J 0
(-450 3450);
DISPLAY 0.872340 (-450 3450);
PAINT GREEN (-450 3450);
DISPLAY INVISIBLE (-450 3450);
FORCEPROP 1 LAST HDL_TAP TRUE
J 0
(-125 3275);
DISPLAY 0.872340 (-125 3275);
DISPLAY INVISIBLE (-125 3275);
FORCEPROP 1 LAST PATH I94
J 0
(-452 3400);
DISPLAY 0.872340 (-452 3400);
PAINT GREEN (-452 3400);
DISPLAY INVISIBLE (-452 3400);
FORCEADD TAP..1
(-450 3500);
FORCEPROP 3 LASTPIN (-500 3500) SIG_NAME M_C_CPU0_SA_DQ<17>
J 0
(-490 3510);
DISPLAY 0.659574 (-490 3510);
PAINT MONO (-490 3510);
DISPLAY INVISIBLE (-490 3510);
FORCEPROP 1 LASTPIN (-500 3500) BN 17
J 0
(-512 3508);
DISPLAY 0.680851 (-512 3508);
PAINT GREEN (-512 3508);
FORCEPROP 2 LAST CDS_LIB standard
J 0
(-450 3500);
PAINT MONO (-450 3500);
DISPLAY INVISIBLE (-450 3500);
FORCEPROP 1 LAST BODY_TYPE PLUMBING
J 0
(-450 3550);
DISPLAY 0.872340 (-450 3550);
PAINT GREEN (-450 3550);
DISPLAY INVISIBLE (-450 3550);
FORCEPROP 1 LAST HDL_TAP TRUE
J 0
(-125 3375);
DISPLAY 0.872340 (-125 3375);
DISPLAY INVISIBLE (-125 3375);
FORCEPROP 1 LAST PATH I95
J 0
(-452 3500);
DISPLAY 0.872340 (-452 3500);
PAINT GREEN (-452 3500);
DISPLAY INVISIBLE (-452 3500);
FORCEADD TAP..1
(-450 3450);
FORCEPROP 3 LASTPIN (-500 3450) SIG_NAME M_C_CPU0_SA_DQ<16>
J 0
(-490 3460);
DISPLAY 0.659574 (-490 3460);
PAINT MONO (-490 3460);
DISPLAY INVISIBLE (-490 3460);
FORCEPROP 1 LASTPIN (-500 3450) BN 16
J 0
(-512 3458);
DISPLAY 0.680851 (-512 3458);
PAINT GREEN (-512 3458);
FORCEPROP 2 LAST CDS_LIB standard
J 0
(-450 3450);
PAINT MONO (-450 3450);
DISPLAY INVISIBLE (-450 3450);
FORCEPROP 1 LAST BODY_TYPE PLUMBING
J 0
(-450 3500);
DISPLAY 0.872340 (-450 3500);
PAINT GREEN (-450 3500);
DISPLAY INVISIBLE (-450 3500);
FORCEPROP 1 LAST HDL_TAP TRUE
J 0
(-125 3325);
DISPLAY 0.872340 (-125 3325);
DISPLAY INVISIBLE (-125 3325);
FORCEPROP 1 LAST PATH I96
J 0
(-452 3450);
DISPLAY 0.872340 (-452 3450);
PAINT GREEN (-452 3450);
DISPLAY INVISIBLE (-452 3450);
FORCEADD TAP..1
(-450 3600);
FORCEPROP 3 LASTPIN (-500 3600) SIG_NAME M_C_CPU0_SA_DQ<19>
J 0
(-490 3610);
DISPLAY 0.659574 (-490 3610);
PAINT MONO (-490 3610);
DISPLAY INVISIBLE (-490 3610);
FORCEPROP 1 LASTPIN (-500 3600) BN 19
J 0
(-512 3608);
DISPLAY 0.680851 (-512 3608);
PAINT GREEN (-512 3608);
FORCEPROP 2 LAST CDS_LIB standard
J 0
(-450 3600);
PAINT MONO (-450 3600);
DISPLAY INVISIBLE (-450 3600);
FORCEPROP 1 LAST BODY_TYPE PLUMBING
J 0
(-450 3650);
DISPLAY 0.872340 (-450 3650);
PAINT GREEN (-450 3650);
DISPLAY INVISIBLE (-450 3650);
FORCEPROP 1 LAST HDL_TAP TRUE
J 0
(-125 3475);
DISPLAY 0.872340 (-125 3475);
DISPLAY INVISIBLE (-125 3475);
FORCEPROP 1 LAST PATH I97
J 0
(-452 3600);
DISPLAY 0.872340 (-452 3600);
PAINT GREEN (-452 3600);
DISPLAY INVISIBLE (-452 3600);
FORCEADD TAP..1
(-450 3550);
FORCEPROP 3 LASTPIN (-500 3550) SIG_NAME M_C_CPU0_SA_DQ<18>
J 0
(-490 3560);
DISPLAY 0.659574 (-490 3560);
PAINT MONO (-490 3560);
DISPLAY INVISIBLE (-490 3560);
FORCEPROP 1 LASTPIN (-500 3550) BN 18
J 0
(-512 3558);
DISPLAY 0.680851 (-512 3558);
PAINT GREEN (-512 3558);
FORCEPROP 2 LAST CDS_LIB standard
J 0
(-450 3550);
PAINT MONO (-450 3550);
DISPLAY INVISIBLE (-450 3550);
FORCEPROP 1 LAST BODY_TYPE PLUMBING
J 0
(-450 3600);
DISPLAY 0.872340 (-450 3600);
PAINT GREEN (-450 3600);
DISPLAY INVISIBLE (-450 3600);
FORCEPROP 1 LAST HDL_TAP TRUE
J 0
(-125 3425);
DISPLAY 0.872340 (-125 3425);
DISPLAY INVISIBLE (-125 3425);
FORCEPROP 1 LAST PATH I98
J 0
(-452 3550);
DISPLAY 0.872340 (-452 3550);
PAINT GREEN (-452 3550);
DISPLAY INVISIBLE (-452 3550);
FORCEADD TAP..1
(-450 3650);
FORCEPROP 3 LASTPIN (-500 3650) SIG_NAME M_C_CPU0_SA_DQ<20>
J 0
(-490 3660);
DISPLAY 0.659574 (-490 3660);
PAINT MONO (-490 3660);
DISPLAY INVISIBLE (-490 3660);
FORCEPROP 1 LASTPIN (-500 3650) BN 20
J 0
(-512 3658);
DISPLAY 0.680851 (-512 3658);
PAINT GREEN (-512 3658);
FORCEPROP 2 LAST CDS_LIB standard
J 0
(-450 3650);
PAINT MONO (-450 3650);
DISPLAY INVISIBLE (-450 3650);
FORCEPROP 1 LAST BODY_TYPE PLUMBING
J 0
(-450 3700);
DISPLAY 0.872340 (-450 3700);
PAINT GREEN (-450 3700);
DISPLAY INVISIBLE (-450 3700);
FORCEPROP 1 LAST HDL_TAP TRUE
J 0
(-125 3525);
DISPLAY 0.872340 (-125 3525);
DISPLAY INVISIBLE (-125 3525);
FORCEPROP 1 LAST PATH I99
J 0
(-452 3650);
DISPLAY 0.872340 (-452 3650);
PAINT GREEN (-452 3650);
DISPLAY INVISIBLE (-452 3650);
FORCEADD CAD_NOTE..1
(1400 -250);
FORCEPROP 0 LAST S1 PLACE THE BYPASS CAPS CLOSE TO DIMM
J 0
(1275 -375);
DISPLAY 1.021277 (1275 -375);
PAINT WHITE (1275 -375);
FORCEPROP 2 LAST CDS_LIB logical_power
J 0
(1400 -250);
PAINT MONO (1400 -250);
DISPLAY INVISIBLE (1400 -250);
FORCEPROP 1 LAST COMMENT_BODY TRUE
J 0
(1425 -150);
DISPLAY 0.978723 (1425 -150);
DISPLAY INVISIBLE (1425 -150);
FORCEADD QUANTA_TITLE_BLOCK_C..1
(5875 -1550);
FORCEPROP 0 LAST CDS_CON_LAST_MODIFIED Fri Aug 25 14:01:06 2023
J 0
(3990 -1535);
PAINT MONO (3990 -1535);
DISPLAY INVISIBLE (3990 -1535);
FORCEPROP 1 LAST CUSTOM_TXT_CDS <CON_LAST_MODIFIED>
J 0
(3990 -1535);
DISPLAY 0.978723 (3990 -1535);
FORCEPROP 2 LAST CUSTOM_TXT_CDS <XR_PAGE_TITLE>
J 0
(-2015 3700);
DISPLAY 0.638298 (-2015 3700);
PAINT PINK (-2015 3700);
DISPLAY INVISIBLE (-2015 3700);
FORCEPROP 2 LAST CUSTOM_TXT_CDS <Q_NUMBER>
J 0
(4472 -1447);
DISPLAY 1.212766 (4472 -1447);
FORCEPROP 1 LAST CUSTOM_TXT_CDS <NAME_2>
J 0
(2700 -1500);
FORCEPROP 1 LAST CUSTOM_TXT_CDS <NAME_1>
J 0
(2700 -1375);
FORCEPROP 1 LAST CUSTOM_TXT_CDS <Q_PROJ>
J 0
(3493 -1448);
DISPLAY 1.212766 (3493 -1448);
FORCEPROP 1 LAST CUSTOM_TXT_CDS <Q_REV>
J 0
(5691 -1447);
DISPLAY 1.212766 (5691 -1447);
FORCEPROP 1 LAST CUSTOM_TXT_CDS <CON_PAGE_NUM> OF <CON_TOTAL_PAGES>
J 0
(5429 -1532);
DISPLAY 0.978723 (5429 -1532);
FORCEPROP 1 LAST Q_TITLE DDR5 - CPU0 CHC DIMM2(BLACK)
J 0
(-3491 -1524);
DISPLAY 2.446809 (-3491 -1524);
PAINT GREEN (-3491 -1524);
FORCEPROP 1 LAST Q_DEPT 
J 1
(2112 -1501);
DISPLAY 1.957447 (2112 -1501);
PAINT GREEN (2112 -1501);
FORCEPROP 1 LAST COMMENT_BODY TRUE
J 0
(5887 -1563);
DISPLAY 0.978723 (5887 -1563);
PAINT GREEN (5887 -1563);
DISPLAY INVISIBLE (5887 -1563);
FORCEPROP 2 LAST CDS_XR_PAGE_TITLE CR-87 : @S9S_MB_2U_LIB.S9S_MB_2U(SCH_1):PAGE87
J 0
(-2015 3700);
DISPLAY 0.638298 (-2015 3700);
PAINT PINK (-2015 3700);
DISPLAY INVISIBLE (-2015 3700);
FORCEPROP 2 LAST PAGE_BORDER TRUE
J 0
(-2015 3700);
DISPLAY 0.638298 (-2015 3700);
PAINT PINK (-2015 3700);
DISPLAY INVISIBLE (-2015 3700);
FORCEPROP 1 LAST CDS_LMAN_SYM_OUTLINE -9475,6775,100,-125
J 0
(5875 -1550);
DISPLAY 0.468085 (5875 -1550);
PAINT GREEN (5875 -1550);
DISPLAY INVISIBLE (5875 -1550);
FORCEPROP 2 LAST CDS_LIB pure_quanta
J 0
(5875 -1550);
PAINT MONO (5875 -1550);
DISPLAY INVISIBLE (5875 -1550);
WIRE 17 -1 (-400 4175)(-400 4225);
WIRE 17 -1 (-400 4125)(-400 4175);
WIRE 17 -1 (-400 4225)(325 4225);
FORCEPROP 2 LAST SIG_NAME M_C_CPU0_SA_DQ<31:0>
J 0
(-335 4235);
DISPLAY 0.680851 (-335 4235);
PAINT WHITE (-335 4235);
WIRE 17 -1 (-2150 2775)(-2150 2825);
WIRE 17 -1 (-2150 2725)(-2150 2775);
WIRE 17 -1 (-2975 2825)(-2150 2825);
FORCEPROP 2 LAST SIG_NAME M_C_CPU0_SA_CB<7:0>
J 0
(-2885 2835);
DISPLAY 0.680851 (-2885 2835);
PAINT WHITE (-2885 2835);
WIRE 17 -1 (-2150 2675)(-2150 2725);
WIRE 17 -1 (-2150 2625)(-2150 2675);
WIRE 17 -1 (-2150 2575)(-2150 2625);
WIRE 17 -1 (-2150 2525)(-2150 2575);
WIRE 17 -1 (-2150 2475)(-2150 2525);
WIRE 17 -1 (-2150 2325)(-2150 2375);
WIRE 17 -1 (-2150 2275)(-2150 2325);
WIRE 17 -1 (-2975 2375)(-2150 2375);
FORCEPROP 2 LAST SIG_NAME M_C_CPU0_SB_CB<7:0>
J 0
(-2885 2385);
DISPLAY 0.680851 (-2885 2385);
PAINT WHITE (-2885 2385);
WIRE 17 -1 (-2150 3925)(-2150 3975);
WIRE 17 -1 (-2150 3975)(-2150 4025);
WIRE 17 -1 (-2150 4025)(-2150 4075);
WIRE 17 -1 (-2150 4075)(-2150 4125);
WIRE 17 -1 (-2150 4125)(-2150 4175);
WIRE 17 -1 (-2150 4175)(-2150 4225);
WIRE 17 -1 (-2975 4225)(-2150 4225);
FORCEPROP 2 LAST SIG_NAME M_C_CPU0_SA_CA<6:0>
J 0
(-2885 4235);
DISPLAY 0.680851 (-2885 4235);
PAINT WHITE (-2885 4235);
WIRE 17 -1 (-2150 3525)(-2150 3575);
WIRE 17 -1 (-2150 3575)(-2150 3625);
WIRE 17 -1 (-2150 3625)(-2150 3675);
WIRE 17 -1 (-2150 3675)(-2150 3725);
WIRE 17 -1 (-2150 3725)(-2150 3775);
WIRE 17 -1 (-2150 3775)(-2150 3825);
WIRE 17 -1 (-2975 3825)(-2150 3825);
FORCEPROP 2 LAST SIG_NAME M_C_CPU0_SB_CA<6:0>
J 0
(-2885 3835);
DISPLAY 0.680851 (-2885 3835);
PAINT WHITE (-2885 3835);
WIRE 17 -1 (-2150 2175)(-2150 2225);
WIRE 17 -1 (-2150 2125)(-2150 2175);
WIRE 17 -1 (-2150 2225)(-2150 2275);
WIRE 17 -1 (-2150 2075)(-2150 2125);
WIRE 17 -1 (-2150 2025)(-2150 2075);
WIRE 17 -1 (-400 4075)(-400 4125);
WIRE 17 -1 (-400 4025)(-400 4075);
WIRE 17 -1 (-400 3975)(-400 4025);
WIRE 17 -1 (-400 3925)(-400 3975);
WIRE 17 -1 (-400 3875)(-400 3925);
WIRE 17 -1 (-400 3825)(-400 3875);
WIRE 17 -1 (-400 3775)(-400 3825);
WIRE 17 -1 (-400 3725)(-400 3775);
WIRE 17 -1 (-400 3675)(-400 3725);
WIRE 17 -1 (-400 3625)(-400 3675);
WIRE 17 -1 (-400 3575)(-400 3625);
WIRE 17 -1 (-400 3525)(-400 3575);
WIRE 17 -1 (-400 3475)(-400 3525);
WIRE 17 -1 (-400 3425)(-400 3475);
WIRE 17 -1 (-400 3375)(-400 3425);
WIRE 17 -1 (-400 3325)(-400 3375);
WIRE 17 -1 (-400 3275)(-400 3325);
WIRE 17 -1 (-400 3225)(-400 3275);
WIRE 17 -1 (-400 3175)(-400 3225);
WIRE 17 -1 (-400 3125)(-400 3175);
WIRE 17 -1 (-400 3075)(-400 3125);
WIRE 17 -1 (-400 3025)(-400 3075);
WIRE 17 -1 (-400 2975)(-400 3025);
WIRE 17 -1 (-400 2925)(-400 2975);
WIRE 17 -1 (-400 2875)(-400 2925);
WIRE 17 -1 (-400 2825)(-400 2875);
WIRE 17 -1 (-400 2775)(-400 2825);
WIRE 17 -1 (-400 2725)(-400 2775);
WIRE 17 -1 (-400 2675)(-400 2725);
WIRE 17 -1 (-400 2525)(-400 2575);
WIRE 17 -1 (-400 2475)(-400 2525);
WIRE 17 -1 (-400 2575)(325 2575);
FORCEPROP 2 LAST SIG_NAME M_C_CPU0_SB_DQ<31:0>
J 0
(-335 2585);
DISPLAY 0.680851 (-335 2585);
PAINT WHITE (-335 2585);
WIRE 17 -1 (-400 2425)(-400 2475);
WIRE 17 -1 (-400 2375)(-400 2425);
WIRE 17 -1 (-400 2325)(-400 2375);
WIRE 17 -1 (-400 2275)(-400 2325);
WIRE 17 -1 (-400 2225)(-400 2275);
WIRE 17 -1 (-400 2175)(-400 2225);
WIRE 17 -1 (-400 2125)(-400 2175);
WIRE 17 -1 (-400 2075)(-400 2125);
WIRE 17 -1 (-400 2025)(-400 2075);
WIRE 17 -1 (-400 1975)(-400 2025);
WIRE 17 -1 (-400 1925)(-400 1975);
WIRE 17 -1 (-400 1875)(-400 1925);
WIRE 17 -1 (-400 1825)(-400 1875);
WIRE 17 -1 (-400 1775)(-400 1825);
WIRE 17 -1 (-400 1725)(-400 1775);
WIRE 17 -1 (-400 1675)(-400 1725);
WIRE 17 -1 (-400 1625)(-400 1675);
WIRE 17 -1 (-400 1575)(-400 1625);
WIRE 17 -1 (-400 1525)(-400 1575);
WIRE 17 -1 (-400 1475)(-400 1525);
WIRE 17 -1 (-400 1425)(-400 1475);
WIRE 17 -1 (-400 1375)(-400 1425);
WIRE 17 -1 (-400 1325)(-400 1375);
WIRE 17 -1 (-400 1275)(-400 1325);
WIRE 17 -1 (-400 1225)(-400 1275);
WIRE 17 -1 (-400 1175)(-400 1225);
WIRE 17 -1 (-400 1125)(-400 1175);
WIRE 17 -1 (-400 1075)(-400 1125);
WIRE 17 -1 (-400 1025)(-400 1075);
WIRE 17 -1 (2350 2275)(2350 2375);
WIRE 17 -1 (2350 2375)(2350 2475);
WIRE 17 -1 (2350 2475)(2350 2575);
WIRE 17 -1 (2350 2675)(2350 2575);
WIRE 17 -1 (2350 2675)(2350 2775);
WIRE 17 -1 (2350 2775)(2350 2875);
WIRE 17 -1 (2350 2875)(2350 2975);
WIRE 17 -1 (2350 2975)(2350 3075);
WIRE 17 -1 (2350 3075)(2350 3175);
WIRE 17 -1 (2350 3175)(3375 3175);
FORCEPROP 2 LAST SIG_NAME M_C_CPU0_SB_DQS_DP<9:0>
J 0
(2590 3185);
DISPLAY 0.680851 (2590 3185);
PAINT WHITE (2590 3185);
WIRE 17 -1 (2350 3325)(2350 3425);
WIRE 17 -1 (2350 3425)(2350 3525);
WIRE 17 -1 (2350 3525)(2350 3625);
WIRE 17 -1 (2350 3725)(2350 3625);
WIRE 17 -1 (2350 3725)(2350 3825);
WIRE 17 -1 (2350 3825)(2350 3925);
WIRE 17 -1 (2350 3925)(2350 4025);
WIRE 17 -1 (2350 4025)(2350 4125);
WIRE 17 -1 (2350 4125)(2350 4225);
WIRE 17 -1 (2350 4225)(3375 4225);
FORCEPROP 2 LAST SIG_NAME M_C_CPU0_SA_DQS_DP<9:0>
J 0
(2590 4235);
DISPLAY 0.680851 (2590 4235);
PAINT WHITE (2590 4235);
WIRE 17 -1 (2525 2325)(2525 2425);
WIRE 17 -1 (2525 2225)(2525 2325);
WIRE 17 -1 (2525 2425)(2525 2525);
WIRE 17 -1 (2525 2625)(2525 2525);
WIRE 17 -1 (2525 2625)(2525 2725);
WIRE 17 -1 (2525 2725)(2525 2825);
WIRE 17 -1 (2525 2825)(2525 2925);
WIRE 17 -1 (2525 2925)(2525 3025);
WIRE 17 -1 (2525 3025)(2525 3125);
WIRE 17 -1 (2525 3125)(3375 3125);
FORCEPROP 2 LAST SIG_NAME M_C_CPU0_SB_DQS_DN<9:0>
J 0
(2590 3135);
DISPLAY 0.680851 (2590 3135);
PAINT WHITE (2590 3135);
WIRE 17 -1 (2525 3275)(2525 3375);
WIRE 17 -1 (2525 3375)(2525 3475);
WIRE 17 -1 (2525 3475)(2525 3575);
WIRE 17 -1 (2525 3675)(2525 3575);
WIRE 17 -1 (2525 3675)(2525 3775);
WIRE 17 -1 (2525 3775)(2525 3875);
WIRE 17 -1 (2525 3875)(2525 3975);
WIRE 17 -1 (2525 3975)(2525 4075);
WIRE 17 -1 (2525 4075)(2525 4175);
WIRE 17 -1 (2525 4175)(3375 4175);
FORCEPROP 2 LAST SIG_NAME M_C_CPU0_SA_DQS_DN<9:0>
J 0
(2590 4185);
DISPLAY 0.680851 (2590 4185);
PAINT WHITE (2590 4185);
WIRE 16 -1 (2275 600)(2275 550);
WIRE 16 -1 (-2925 2025)(-2925 1750);
WIRE 16 -1 (3975 4700)(3975 4200);
WIRE 16 -1 (1275 425)(1275 600);
WIRE 16 -1 (-1875 -125)(-1875 -50);
WIRE 16 -1 (5675 850)(5675 550);
WIRE 16 -1 (5675 900)(5675 850);
WIRE 16 -1 (5425 850)(5675 850);
WIRE 16 -1 (3975 550)(3975 950);
WIRE 16 -1 (2900 0)(2900 75);
WIRE 16 -1 (1275 225)(1275 0);
WIRE 16 3135 (925 825)(925 -475);
WIRE 16 3135 (3525 825)(925 825);
WIRE 16 3135 (925 -475)(3525 -475);
WIRE 16 3135 (3525 -475)(3525 825);
WIRE 16 -1 (2275 75)(2275 225);
WIRE 16 -1 (2900 75)(2275 75);
WIRE 16 -1 (2900 75)(2900 225);
WIRE 16 -1 (2275 550)(2275 425);
WIRE 16 -1 (2900 550)(2275 550);
WIRE 16 -1 (2900 425)(2900 550);
WIRE 16 -1 (-1875 1700)(-2900 1700);
FORCEPROP 2 LAST SIG_NAME PD_CHC_CPU0_DIMM2_SAA
J 0
(-2910 1710);
DISPLAY 0.680851 (-2910 1710);
PAINT WHITE (-2910 1710);
WIRE 16 -1 (-1875 1650)(-2900 1650);
FORCEPROP 2 LAST SIG_NAME I3C_SPD_DDRABCD_CPU0_LVC1_SDA
J 0
(-2910 1660);
DISPLAY 0.680851 (-2910 1660);
PAINT WHITE (-2910 1660);
WIRE 16 -1 (-3425 1500)(-3250 1500);
WIRE 16 -1 (-3425 1600)(-3425 1500);
WIRE 16 -1 (-3425 1600)(-1875 1600);
FORCEPROP 2 LAST SIG_NAME I3C_SPD_DDRABCD_CPU0_LVC1_SCL_R6
J 0
(-2935 1610);
DISPLAY 0.680851 (-2935 1610);
PAINT WHITE (-2935 1610);
WIRE 16 -1 (-2925 1750)(-1875 1750);
WIRE 16 -1 (-1875 1850)(-2975 1850);
FORCEPROP 2 LAST SIG_NAME M_C_CPU0_ALERT_N
J 0
(-2887 1859);
DISPLAY 0.680851 (-2887 1859);
PAINT WHITE (-2887 1859);
WIRE 16 -1 (-2250 1950)(-2975 1950);
FORCEPROP 2 LAST SIG_NAME RST_M_CD_CPU0_FPGA_N
J 0
(-2887 1959);
DISPLAY 0.680851 (-2887 1959);
PAINT WHITE (-2887 1959);
WIRE 16 -1 (-2250 1950)(-2250 1900);
WIRE 16 -1 (-2250 1900)(-1875 1900);
WIRE 16 -1 (-1825 1450)(-1875 1450);
WIRE 16 -1 (-1825 1500)(-1825 1450);
WIRE 16 -1 (-3050 1500)(-1825 1500);
FORCEPROP 2 LAST SIG_NAME I3C_SPD_DDRABCD_CPU0_LVC1_SCL
J 0
(-2935 1510);
DISPLAY 0.680851 (-2935 1510);
PAINT WHITE (-2935 1510);
WIRE 16 -1 (-1875 1150)(-2975 1150);
FORCEPROP 2 LAST SIG_NAME TP_CHC_CPU0_DIMM2_FRU_4
J 0
(-2887 1159);
DISPLAY 0.680851 (-2887 1159);
PAINT WHITE (-2887 1159);
WIRE 16 -1 (-1875 1200)(-2975 1200);
FORCEPROP 2 LAST SIG_NAME TP_CHC_CPU0_DIMM2_FRU_5
J 0
(-2887 1209);
DISPLAY 0.680851 (-2887 1209);
PAINT WHITE (-2887 1209);
WIRE 16 -1 (-1875 1350)(-2975 1350);
FORCEPROP 2 LAST SIG_NAME PWRGD_CHC_CPU0_DIMM2
J 0
(-2887 1359);
DISPLAY 0.680851 (-2887 1359);
PAINT WHITE (-2887 1359);
WIRE 16 -1 (-1875 3050)(-2975 3050);
FORCEPROP 2 LAST SIG_NAME M_C_CPU0_SB_CS_N<2>
J 0
(-2887 3059);
DISPLAY 0.680851 (-2887 3059);
PAINT WHITE (-2887 3059);
WIRE 16 -1 (2150 2800)(2425 2800);
WIRE 16 -1 (2150 4150)(2425 4150);
WIRE 16 -1 (2150 4050)(2425 4050);
WIRE 16 -1 (2150 3850)(2425 3850);
WIRE 16 -1 (2150 3950)(2425 3950);
WIRE 16 -1 (2150 3750)(2425 3750);
WIRE 16 -1 (2150 3650)(2425 3650);
WIRE 16 -1 (2150 3550)(2425 3550);
WIRE 16 -1 (2150 3350)(2425 3350);
WIRE 16 -1 (2150 3450)(2425 3450);
WIRE 16 -1 (2150 3250)(2425 3250);
WIRE 16 -1 (2150 3100)(2425 3100);
WIRE 16 -1 (2150 3000)(2425 3000);
WIRE 16 -1 (2150 2900)(2425 2900);
WIRE 16 -1 (2150 2700)(2425 2700);
WIRE 16 -1 (2150 2600)(2425 2600);
WIRE 16 -1 (2150 2500)(2425 2500);
WIRE 16 -1 (2150 2400)(2425 2400);
WIRE 16 -1 (2150 2200)(2425 2200);
WIRE 16 -1 (2150 2300)(2425 2300);
WIRE 16 -1 (2150 4200)(2250 4200);
WIRE 16 -1 (2150 4100)(2250 4100);
WIRE 16 -1 (2150 4000)(2250 4000);
WIRE 16 -1 (2150 3900)(2250 3900);
WIRE 16 -1 (2150 3800)(2250 3800);
WIRE 16 -1 (2150 3700)(2250 3700);
WIRE 16 -1 (2150 3600)(2250 3600);
WIRE 16 -1 (2150 3500)(2250 3500);
WIRE 16 -1 (2150 3400)(2250 3400);
WIRE 16 -1 (2150 3300)(2250 3300);
WIRE 16 -1 (2150 3150)(2250 3150);
WIRE 16 -1 (2150 3050)(2250 3050);
WIRE 16 -1 (2150 2950)(2250 2950);
WIRE 16 -1 (2150 2850)(2250 2850);
WIRE 16 -1 (2150 2750)(2250 2750);
WIRE 16 -1 (2150 2650)(2250 2650);
WIRE 16 -1 (2150 2550)(2250 2550);
WIRE 16 -1 (2150 2450)(2250 2450);
WIRE 16 -1 (2150 2350)(2250 2350);
WIRE 16 -1 (2150 2250)(2250 2250);
WIRE 16 -1 (-1875 2950)(-2975 2950);
FORCEPROP 2 LAST SIG_NAME M_C_CPU0_CLK_DP<1>
J 0
(-2887 2959);
DISPLAY 0.680851 (-2887 2959);
PAINT WHITE (-2887 2959);
WIRE 16 -1 (-1875 1100)(-2975 1100);
FORCEPROP 2 LAST SIG_NAME TP_CHC_CPU0_DIMM2_FRU_3
J 0
(-2887 1109);
DISPLAY 0.680851 (-2887 1109);
PAINT WHITE (-2887 1109);
WIRE 16 -1 (-1875 1050)(-2975 1050);
FORCEPROP 2 LAST SIG_NAME TP_CHC_CPU0_DIMM2_FRU_2
J 0
(-2887 1059);
DISPLAY 0.680851 (-2887 1059);
PAINT WHITE (-2887 1059);
WIRE 16 -1 (-1875 950)(-2975 950);
FORCEPROP 2 LAST SIG_NAME TP_CHC_CPU0_DIMM2_FRU_0
J 0
(-2887 959);
DISPLAY 0.680851 (-2887 959);
PAINT WHITE (-2887 959);
WIRE 16 -1 (-1875 1250)(-2975 1250);
FORCEPROP 2 LAST SIG_NAME TP_CHC_CPU0_DIMM2_FRU_6
J 0
(-2887 1259);
DISPLAY 0.680851 (-2887 1259);
PAINT WHITE (-2887 1259);
WIRE 16 -1 (-675 1350)(-500 1350);
WIRE 16 -1 (4225 4100)(3975 4100);
WIRE 16 -1 (3975 4150)(3975 4100);
WIRE 16 -1 (3975 4150)(4225 4150);
WIRE 16 -1 (3975 4200)(3975 4150);
WIRE 16 -1 (4225 4200)(3975 4200);
WIRE 16 -1 (-2050 3550)(-1875 3550);
WIRE 16 -1 (-1875 3400)(-2975 3400);
FORCEPROP 2 LAST SIG_NAME M_C_CPU0_SA_PAR
J 0
(-2887 3409);
DISPLAY 0.680851 (-2887 3409);
PAINT WHITE (-2887 3409);
WIRE 16 -1 (-1875 3350)(-2975 3350);
FORCEPROP 2 LAST SIG_NAME M_C_CPU0_SB_PAR
J 0
(-2887 3359);
DISPLAY 0.680851 (-2887 3359);
PAINT WHITE (-2887 3359);
WIRE 16 -1 (-1875 3250)(-2975 3250);
FORCEPROP 2 LAST SIG_NAME M_C_CPU0_SA_CS_N<3>
J 0
(-2887 3259);
DISPLAY 0.680851 (-2887 3259);
PAINT WHITE (-2887 3259);
WIRE 16 -1 (-1875 3200)(-2975 3200);
FORCEPROP 2 LAST SIG_NAME M_C_CPU0_SA_CS_N<2>
J 0
(-2887 3209);
DISPLAY 0.680851 (-2887 3209);
PAINT WHITE (-2887 3209);
WIRE 16 -1 (-1875 3100)(-2975 3100);
FORCEPROP 2 LAST SIG_NAME M_C_CPU0_SB_CS_N<3>
J 0
(-2887 3109);
DISPLAY 0.680851 (-2887 3109);
PAINT WHITE (-2887 3109);
WIRE 16 -1 (-1875 2900)(-2975 2900);
FORCEPROP 2 LAST SIG_NAME M_C_CPU0_CLK_DN<1>
J 0
(-2887 2909);
DISPLAY 0.680851 (-2887 2909);
PAINT WHITE (-2887 2909);
WIRE 16 -1 (-2050 2200)(-1875 2200);
WIRE 16 -1 (-2050 2250)(-1875 2250);
WIRE 16 -1 (-675 2000)(-500 2000);
WIRE 16 -1 (3975 950)(4225 950);
WIRE 16 -1 (3975 950)(3975 1000);
WIRE 16 -1 (3975 1000)(4225 1000);
WIRE 16 -1 (3975 1000)(3975 1050);
WIRE 16 -1 (3975 1050)(4225 1050);
WIRE 16 -1 (3975 1050)(3975 1100);
WIRE 16 -1 (3975 1100)(4225 1100);
WIRE 16 -1 (3975 1100)(3975 1150);
WIRE 16 -1 (3975 1150)(4225 1150);
WIRE 16 -1 (3975 1150)(3975 1200);
WIRE 16 -1 (3975 1200)(4225 1200);
WIRE 16 -1 (3975 1200)(3975 1250);
WIRE 16 -1 (3975 1250)(4225 1250);
WIRE 16 -1 (3975 1250)(3975 1300);
WIRE 16 -1 (3975 1300)(4225 1300);
WIRE 16 -1 (3975 1300)(3975 1350);
WIRE 16 -1 (3975 1350)(4225 1350);
WIRE 16 -1 (3975 1350)(3975 1400);
WIRE 16 -1 (3975 1400)(4225 1400);
WIRE 16 -1 (3975 1400)(3975 1450);
WIRE 16 -1 (4225 1450)(3975 1450);
WIRE 16 -1 (3975 1450)(3975 1500);
WIRE 16 -1 (3975 1500)(4225 1500);
WIRE 16 -1 (3975 1500)(3975 1550);
WIRE 16 -1 (3975 1550)(4225 1550);
WIRE 16 -1 (3975 1550)(3975 1600);
WIRE 16 -1 (3975 1600)(4225 1600);
WIRE 16 -1 (3975 1600)(3975 1650);
WIRE 16 -1 (3975 1650)(4225 1650);
WIRE 16 -1 (3975 1650)(3975 1700);
WIRE 16 -1 (3975 1700)(4225 1700);
WIRE 16 -1 (3975 1700)(3975 1750);
WIRE 16 -1 (3975 1750)(4225 1750);
WIRE 16 -1 (3975 1750)(3975 1800);
WIRE 16 -1 (3975 1800)(4225 1800);
WIRE 16 -1 (3975 1800)(3975 1850);
WIRE 16 -1 (3975 1850)(4225 1850);
WIRE 16 -1 (3975 1850)(3975 1900);
WIRE 16 -1 (3975 1900)(4225 1900);
WIRE 16 -1 (3975 1900)(3975 1950);
WIRE 16 -1 (4225 1950)(3975 1950);
WIRE 16 -1 (3975 1950)(3975 2000);
WIRE 16 -1 (3975 2000)(4225 2000);
WIRE 16 -1 (3975 2000)(3975 2050);
WIRE 16 -1 (3975 2050)(4225 2050);
WIRE 16 -1 (3975 2050)(3975 2100);
WIRE 16 -1 (3975 2100)(4225 2100);
WIRE 16 -1 (3975 2100)(3975 2150);
WIRE 16 -1 (3975 2150)(4225 2150);
WIRE 16 -1 (3975 2150)(3975 2200);
WIRE 16 -1 (3975 2200)(4225 2200);
WIRE 16 -1 (3975 2200)(3975 2250);
WIRE 16 -1 (3975 2250)(4225 2250);
WIRE 16 -1 (3975 2250)(3975 2300);
WIRE 16 -1 (3975 2300)(4225 2300);
WIRE 16 -1 (3975 2300)(3975 2350);
WIRE 16 -1 (3975 2350)(4225 2350);
WIRE 16 -1 (3975 2350)(3975 2400);
WIRE 16 -1 (3975 2400)(4225 2400);
WIRE 16 -1 (3975 2400)(3975 2450);
WIRE 16 -1 (4225 2450)(3975 2450);
WIRE 16 -1 (3975 2450)(3975 2500);
WIRE 16 -1 (3975 2500)(4225 2500);
WIRE 16 -1 (3975 2500)(3975 2550);
WIRE 16 -1 (3975 2550)(4225 2550);
WIRE 16 -1 (3975 2550)(3975 2600);
WIRE 16 -1 (3975 2600)(4225 2600);
WIRE 16 -1 (3975 2600)(3975 2650);
WIRE 16 -1 (3975 2650)(4225 2650);
WIRE 16 -1 (3975 2650)(3975 2700);
WIRE 16 -1 (3975 2700)(4225 2700);
WIRE 16 -1 (3975 2700)(3975 2750);
WIRE 16 -1 (3975 2750)(4225 2750);
WIRE 16 -1 (3975 2750)(3975 2800);
WIRE 16 -1 (3975 2800)(4225 2800);
WIRE 16 -1 (3975 2800)(3975 2850);
WIRE 16 -1 (3975 2850)(4225 2850);
WIRE 16 -1 (3975 2850)(3975 2900);
WIRE 16 -1 (3975 2900)(4225 2900);
WIRE 16 -1 (3975 2900)(3975 2950);
WIRE 16 -1 (4225 2950)(3975 2950);
WIRE 16 -1 (3975 2950)(3975 3000);
WIRE 16 -1 (3975 3000)(4225 3000);
WIRE 16 -1 (3975 3000)(3975 3050);
WIRE 16 -1 (3975 3050)(4225 3050);
WIRE 16 -1 (3975 3050)(3975 3100);
WIRE 16 -1 (3975 3100)(4225 3100);
WIRE 16 -1 (3975 3100)(3975 3150);
WIRE 16 -1 (3975 3150)(4225 3150);
WIRE 16 -1 (3975 3150)(3975 3200);
WIRE 16 -1 (3975 3200)(4225 3200);
WIRE 16 -1 (3975 3200)(3975 3250);
WIRE 16 -1 (3975 3250)(4225 3250);
WIRE 16 -1 (3975 3250)(3975 3300);
WIRE 16 -1 (3975 3300)(4225 3300);
WIRE 16 -1 (3975 3300)(3975 3350);
WIRE 16 -1 (3975 3350)(4225 3350);
WIRE 16 -1 (3975 3350)(3975 3400);
WIRE 16 -1 (3975 3400)(4225 3400);
WIRE 16 -1 (3975 3400)(3975 3450);
WIRE 16 -1 (4225 3450)(3975 3450);
WIRE 16 -1 (3975 3450)(3975 3500);
WIRE 16 -1 (3975 3500)(4225 3500);
WIRE 16 -1 (3975 3500)(3975 3550);
WIRE 16 -1 (3975 3550)(4225 3550);
WIRE 16 -1 (3975 3550)(3975 3600);
WIRE 16 -1 (3975 3600)(4225 3600);
WIRE 16 -1 (3975 3600)(3975 3650);
WIRE 16 -1 (3975 3650)(4225 3650);
WIRE 16 -1 (3975 3650)(3975 3700);
WIRE 16 -1 (3975 3700)(4225 3700);
WIRE 16 -1 (3975 3700)(3975 3750);
WIRE 16 -1 (3975 3750)(4225 3750);
WIRE 16 -1 (3975 3750)(3975 3800);
WIRE 16 -1 (3975 3800)(4225 3800);
WIRE 16 -1 (3975 3800)(3975 3850);
WIRE 16 -1 (3975 3850)(4225 3850);
WIRE 16 -1 (3975 3850)(3975 3900);
WIRE 16 -1 (3975 3900)(4225 3900);
WIRE 16 -1 (3975 3900)(3975 3950);
WIRE 16 -1 (4225 3950)(3975 3950);
WIRE 16 -1 (3975 3950)(3975 4000);
WIRE 16 -1 (3975 4000)(4225 4000);
WIRE 16 -1 (3975 4000)(3975 4050);
WIRE 16 -1 (4225 4050)(3975 4050);
WIRE 16 -1 (5425 900)(5675 900);
WIRE 16 -1 (5425 950)(5675 950);
WIRE 16 -1 (5675 950)(5675 900);
WIRE 16 -1 (5675 1050)(5675 950);
WIRE 16 -1 (5425 1050)(5675 1050);
WIRE 16 -1 (5425 1100)(5675 1100);
WIRE 16 -1 (5675 1100)(5675 1050);
WIRE 16 -1 (5425 1150)(5675 1150);
WIRE 16 -1 (5675 1100)(5675 1150);
WIRE 16 -1 (5425 1200)(5675 1200);
WIRE 16 -1 (5675 1200)(5675 1150);
WIRE 16 -1 (5425 1250)(5675 1250);
WIRE 16 -1 (5675 1250)(5675 1200);
WIRE 16 -1 (5425 1300)(5675 1300);
WIRE 16 -1 (5675 1300)(5675 1250);
WIRE 16 -1 (5425 1350)(5675 1350);
WIRE 16 -1 (5675 1350)(5675 1300);
WIRE 16 -1 (5425 1400)(5675 1400);
WIRE 16 -1 (5675 1400)(5675 1350);
WIRE 16 -1 (5425 1450)(5675 1450);
WIRE 16 -1 (5675 1450)(5675 1400);
WIRE 16 -1 (5675 1500)(5425 1500);
WIRE 16 -1 (5675 1500)(5675 1450);
WIRE 16 -1 (5675 1550)(5425 1550);
WIRE 16 -1 (5675 1550)(5675 1500);
WIRE 16 -1 (5675 1600)(5425 1600);
WIRE 16 -1 (5675 1600)(5675 1550);
WIRE 16 -1 (5425 1650)(5675 1650);
WIRE 16 -1 (5675 1600)(5675 1650);
WIRE 16 -1 (5675 1700)(5425 1700);
WIRE 16 -1 (5675 1650)(5675 1700);
WIRE 16 -1 (5675 1750)(5425 1750);
WIRE 16 -1 (5675 1750)(5675 1700);
WIRE 16 -1 (5675 1800)(5425 1800);
WIRE 16 -1 (5675 1800)(5675 1750);
WIRE 16 -1 (5675 1850)(5425 1850);
WIRE 16 -1 (5675 1850)(5675 1800);
WIRE 16 -1 (5425 1900)(5675 1900);
WIRE 16 -1 (5675 1900)(5675 1850);
WIRE 16 -1 (5425 1950)(5675 1950);
WIRE 16 -1 (5675 1950)(5675 1900);
WIRE 16 -1 (5425 2000)(5675 2000);
WIRE 16 -1 (5675 1950)(5675 2000);
WIRE 16 -1 (5675 2050)(5675 2000);
WIRE 16 -1 (5425 2050)(5675 2050);
WIRE 16 -1 (5425 2100)(5675 2100);
WIRE 16 -1 (5675 2100)(5675 2050);
WIRE 16 -1 (5425 2150)(5675 2150);
WIRE 16 -1 (5675 2150)(5675 2100);
WIRE 16 -1 (5425 2200)(5675 2200);
WIRE 16 -1 (5675 2200)(5675 2150);
WIRE 16 -1 (5425 2250)(5675 2250);
WIRE 16 -1 (5675 2250)(5675 2200);
WIRE 16 -1 (5675 2300)(5425 2300);
WIRE 16 -1 (5675 2300)(5675 2250);
WIRE 16 -1 (5675 2350)(5425 2350);
WIRE 16 -1 (5675 2350)(5675 2300);
WIRE 16 -1 (5425 2400)(5675 2400);
WIRE 16 -1 (5675 2400)(5675 2350);
WIRE 16 -1 (5425 2450)(5675 2450);
WIRE 16 -1 (5675 2450)(5675 2400);
WIRE 16 -1 (5425 2500)(5675 2500);
WIRE 16 -1 (5675 2450)(5675 2500);
WIRE 16 -1 (5425 2550)(5675 2550);
WIRE 16 -1 (5675 2550)(5675 2500);
WIRE 16 -1 (5425 2600)(5675 2600);
WIRE 16 -1 (5675 2600)(5675 2550);
WIRE 16 -1 (5425 2650)(5675 2650);
WIRE 16 -1 (5675 2650)(5675 2600);
WIRE 16 -1 (5425 2700)(5675 2700);
WIRE 16 -1 (5675 2700)(5675 2650);
WIRE 16 -1 (5425 2750)(5675 2750);
WIRE 16 -1 (5675 2750)(5675 2700);
WIRE 16 -1 (5675 2800)(5425 2800);
WIRE 16 -1 (5675 2800)(5675 2750);
WIRE 16 -1 (5675 2850)(5425 2850);
WIRE 16 -1 (5675 2850)(5675 2800);
WIRE 16 -1 (5425 2900)(5675 2900);
WIRE 16 -1 (5675 2900)(5675 2850);
WIRE 16 -1 (5425 2950)(5675 2950);
WIRE 16 -1 (5675 2950)(5675 2900);
WIRE 16 -1 (5425 3000)(5675 3000);
WIRE 16 -1 (5675 2950)(5675 3000);
WIRE 16 -1 (5425 3050)(5675 3050);
WIRE 16 -1 (5675 3050)(5675 3000);
WIRE 16 -1 (5675 3100)(5675 3050);
WIRE 16 -1 (5425 3100)(5675 3100);
WIRE 16 -1 (5425 3150)(5675 3150);
WIRE 16 -1 (5675 3150)(5675 3100);
WIRE 16 -1 (5425 3200)(5675 3200);
WIRE 16 -1 (5675 3200)(5675 3150);
WIRE 16 -1 (5425 3250)(5675 3250);
WIRE 16 -1 (5675 3250)(5675 3200);
WIRE 16 -1 (5675 3300)(5425 3300);
WIRE 16 -1 (5675 3300)(5675 3250);
WIRE 16 -1 (5675 3350)(5425 3350);
WIRE 16 -1 (5675 3350)(5675 3300);
WIRE 16 -1 (5425 3400)(5675 3400);
WIRE 16 -1 (5675 3400)(5675 3350);
WIRE 16 -1 (5425 3450)(5675 3450);
WIRE 16 -1 (5675 3450)(5675 3400);
WIRE 16 -1 (5425 3500)(5675 3500);
WIRE 16 -1 (5675 3450)(5675 3500);
WIRE 16 -1 (5425 3550)(5675 3550);
WIRE 16 -1 (5675 3550)(5675 3500);
WIRE 16 -1 (5425 3600)(5675 3600);
WIRE 16 -1 (5675 3600)(5675 3550);
WIRE 16 -1 (5425 3650)(5675 3650);
WIRE 16 -1 (5675 3650)(5675 3600);
WIRE 16 -1 (5425 3700)(5675 3700);
WIRE 16 -1 (5675 3700)(5675 3650);
WIRE 16 -1 (5425 3750)(5675 3750);
WIRE 16 -1 (5675 3750)(5675 3700);
WIRE 16 -1 (5425 3800)(5675 3800);
WIRE 16 -1 (5675 3800)(5675 3750);
WIRE 16 -1 (5425 3850)(5675 3850);
WIRE 16 -1 (5675 3850)(5675 3800);
WIRE 16 -1 (5425 3900)(5675 3900);
WIRE 16 -1 (5675 3900)(5675 3850);
WIRE 16 -1 (5425 3950)(5675 3950);
WIRE 16 -1 (5675 3950)(5675 3900);
WIRE 16 -1 (5425 4000)(5675 4000);
WIRE 16 -1 (5675 4000)(5675 3950);
WIRE 16 -1 (5425 4050)(5675 4050);
WIRE 16 -1 (5675 4050)(5675 4000);
WIRE 16 -1 (5675 4100)(5675 4050);
WIRE 16 -1 (5425 4100)(5675 4100);
WIRE 16 -1 (5425 4150)(5675 4150);
WIRE 16 -1 (5675 4150)(5675 4100);
WIRE 16 -1 (5675 4200)(5675 4150);
WIRE 16 -1 (5425 4200)(5675 4200);
WIRE 16 -1 (-675 1300)(-500 1300);
WIRE 16 -1 (-1875 1000)(-2975 1000);
FORCEPROP 2 LAST SIG_NAME TP_CHC_CPU0_DIMM2_FRU_1
J 0
(-2887 1009);
DISPLAY 0.680851 (-2887 1009);
PAINT WHITE (-2887 1009);
WIRE 16 -1 (-1875 750)(-2975 750);
FORCEPROP 2 LAST SIG_NAME M_C_CPU0_SB_RSP<1>
J 0
(-2887 759);
DISPLAY 0.680851 (-2887 759);
PAINT WHITE (-2887 759);
WIRE 16 -1 (-1875 800)(-2975 800);
FORCEPROP 2 LAST SIG_NAME M_C_CPU0_SA_RSP<1>
J 0
(-2887 809);
DISPLAY 0.680851 (-2887 809);
PAINT WHITE (-2887 809);
WIRE 16 -1 (-675 1000)(-500 1000);
WIRE 16 -1 (-675 1050)(-500 1050);
WIRE 16 -1 (-675 1100)(-500 1100);
WIRE 16 -1 (-675 1150)(-500 1150);
WIRE 16 -1 (-675 1200)(-500 1200);
WIRE 16 -1 (-675 1250)(-500 1250);
WIRE 16 -1 (-675 1400)(-500 1400);
WIRE 16 -1 (-675 1450)(-500 1450);
WIRE 16 -1 (-675 1500)(-500 1500);
WIRE 16 -1 (-675 1550)(-500 1550);
WIRE 16 -1 (-675 1600)(-500 1600);
WIRE 16 -1 (-675 1650)(-500 1650);
WIRE 16 -1 (-675 1700)(-500 1700);
WIRE 16 -1 (-675 1750)(-500 1750);
WIRE 16 -1 (-675 1800)(-500 1800);
WIRE 16 -1 (-675 1850)(-500 1850);
WIRE 16 -1 (-675 1900)(-500 1900);
WIRE 16 -1 (-675 1950)(-500 1950);
WIRE 16 -1 (-675 2050)(-500 2050);
WIRE 16 -1 (-675 2100)(-500 2100);
WIRE 16 -1 (-675 2150)(-500 2150);
WIRE 16 -1 (-675 2200)(-500 2200);
WIRE 16 -1 (-675 2250)(-500 2250);
WIRE 16 -1 (-675 2300)(-500 2300);
WIRE 16 -1 (-675 2350)(-500 2350);
WIRE 16 -1 (-675 2400)(-500 2400);
WIRE 16 -1 (-675 2450)(-500 2450);
WIRE 16 -1 (-675 2500)(-500 2500);
WIRE 16 -1 (-675 2550)(-500 2550);
WIRE 16 -1 (-675 2650)(-500 2650);
WIRE 16 -1 (-675 2700)(-500 2700);
WIRE 16 -1 (-675 2750)(-500 2750);
WIRE 16 -1 (-675 2800)(-500 2800);
WIRE 16 -1 (-675 2850)(-500 2850);
WIRE 16 -1 (-675 2900)(-500 2900);
WIRE 16 -1 (-675 2950)(-500 2950);
WIRE 16 -1 (-675 3000)(-500 3000);
WIRE 16 -1 (-675 3050)(-500 3050);
WIRE 16 -1 (-675 3100)(-500 3100);
WIRE 16 -1 (-675 3150)(-500 3150);
WIRE 16 -1 (-675 3200)(-500 3200);
WIRE 16 -1 (-675 3250)(-500 3250);
WIRE 16 -1 (-675 3300)(-500 3300);
WIRE 16 -1 (-675 3350)(-500 3350);
WIRE 16 -1 (-675 3400)(-500 3400);
WIRE 16 -1 (-675 3450)(-500 3450);
WIRE 16 -1 (-675 3500)(-500 3500);
WIRE 16 -1 (-675 3550)(-500 3550);
WIRE 16 -1 (-675 3600)(-500 3600);
WIRE 16 -1 (-675 3650)(-500 3650);
WIRE 16 -1 (-675 3700)(-500 3700);
WIRE 16 -1 (-675 3750)(-500 3750);
WIRE 16 -1 (-675 3800)(-500 3800);
WIRE 16 -1 (-675 3850)(-500 3850);
WIRE 16 -1 (-675 3900)(-500 3900);
WIRE 16 -1 (-675 3950)(-500 3950);
WIRE 16 -1 (-675 4000)(-500 4000);
WIRE 16 -1 (-675 4050)(-500 4050);
WIRE 16 -1 (-675 4100)(-500 4100);
WIRE 16 -1 (-675 4150)(-500 4150);
WIRE 16 -1 (-2050 2000)(-1875 2000);
WIRE 16 -1 (-2050 2050)(-1875 2050);
WIRE 16 -1 (-2050 2100)(-1875 2100);
WIRE 16 -1 (-2050 2150)(-1875 2150);
WIRE 16 -1 (-2050 2300)(-1875 2300);
WIRE 16 -1 (-2050 2450)(-1875 2450);
WIRE 16 -1 (-2050 2550)(-1875 2550);
WIRE 16 -1 (-2050 2600)(-1875 2600);
WIRE 16 -1 (-2050 2700)(-1875 2700);
WIRE 16 -1 (-2050 2750)(-1875 2750);
WIRE 16 -1 (-2050 3800)(-1875 3800);
WIRE 16 -1 (-2050 4200)(-1875 4200);
WIRE 16 -1 (-2050 3750)(-1875 3750);
WIRE 16 -1 (-2050 4150)(-1875 4150);
WIRE 16 -1 (-2050 3700)(-1875 3700);
WIRE 16 -1 (-2050 4100)(-1875 4100);
WIRE 16 -1 (-2050 3650)(-1875 3650);
WIRE 16 -1 (-2050 4050)(-1875 4050);
WIRE 16 -1 (-2050 3600)(-1875 3600);
WIRE 16 -1 (-2050 4000)(-1875 4000);
WIRE 16 -1 (-2050 3950)(-1875 3950);
WIRE 16 -1 (-2050 3500)(-1875 3500);
WIRE 16 -1 (-2050 3900)(-1875 3900);
WIRE 16 -1 (-2050 2350)(-1875 2350);
WIRE 16 -1 (-2050 2500)(-1875 2500);
WIRE 16 -1 (-2050 2650)(-1875 2650);
WIRE 16 -1 (-2050 2800)(-1875 2800);
WIRE 16 -1 (-675 4200)(-500 4200);
WIRE 16 -1 (-1875 250)(-2975 250);
FORCEPROP 2 LAST SIG_NAME PD_CHC_CPU0_DIMM2_SAA
J 0
(-2887 259);
DISPLAY 0.680851 (-2887 259);
PAINT WHITE (-2887 259);
WIRE 16 -1 (-1875 150)(-1875 250);
DOT 1 (5675 850);
DOT 1 (5675 900);
DOT 1 (5675 950);
DOT 1 (2275 550);
DOT 1 (2900 75);
DOT 1 (3975 950);
DOT 1 (3975 1000);
DOT 1 (3975 1150);
DOT 1 (3975 1100);
DOT 1 (3975 1200);
DOT 1 (3975 1250);
DOT 1 (3975 1450);
DOT 1 (3975 1400);
DOT 1 (3975 1350);
DOT 1 (3975 1300);
DOT 1 (3975 1500);
DOT 1 (3975 1650);
DOT 1 (3975 1700);
DOT 1 (3975 1600);
DOT 1 (3975 1550);
DOT 1 (3975 1750);
DOT 1 (3975 1800);
DOT 1 (3975 1900);
DOT 1 (3975 1950);
DOT 1 (3975 1850);
DOT 1 (3975 2000);
DOT 1 (3975 2050);
DOT 1 (3975 2200);
DOT 1 (3975 2150);
DOT 1 (3975 2100);
DOT 1 (3975 2250);
DOT 1 (3975 2300);
DOT 1 (3975 2500);
DOT 1 (3975 2450);
DOT 1 (3975 2350);
DOT 1 (3975 2550);
DOT 1 (3975 2750);
DOT 1 (3975 2700);
DOT 1 (3975 2650);
DOT 1 (3975 2600);
DOT 1 (3975 2800);
DOT 1 (3975 3000);
DOT 1 (3975 2900);
DOT 1 (3975 2950);
DOT 1 (3975 2850);
DOT 1 (3975 3050);
DOT 1 (3975 3200);
DOT 1 (3975 3250);
DOT 1 (3975 3300);
DOT 1 (3975 3450);
DOT 1 (3975 3400);
DOT 1 (3975 3500);
DOT 1 (3975 3350);
DOT 1 (3975 3550);
DOT 1 (3975 3700);
DOT 1 (3975 3750);
DOT 1 (3975 3650);
DOT 1 (3975 3600);
DOT 1 (3975 3800);
DOT 1 (3975 3850);
DOT 1 (3975 3950);
DOT 1 (3975 4000);
DOT 1 (3975 3900);
DOT 1 (3975 4200);
DOT 1 (3975 4150);
DOT 1 (5675 1050);
DOT 1 (5675 1100);
DOT 1 (5675 1150);
DOT 1 (5675 1200);
DOT 1 (5675 1250);
DOT 1 (5675 1300);
DOT 1 (5675 1350);
DOT 1 (5675 1400);
DOT 1 (5675 1450);
DOT 1 (5675 1500);
DOT 1 (5675 1550);
DOT 1 (5675 1600);
DOT 1 (5675 1650);
DOT 1 (5675 1700);
DOT 1 (5675 1750);
DOT 1 (5675 1800);
DOT 1 (5675 1850);
DOT 1 (5675 1900);
DOT 1 (5675 1950);
DOT 1 (5675 2000);
DOT 1 (5675 2050);
DOT 1 (5675 2100);
DOT 1 (5675 2150);
DOT 1 (5675 2200);
DOT 1 (5675 2250);
DOT 1 (5675 2300);
DOT 1 (5675 2350);
DOT 1 (5675 2400);
DOT 1 (5675 2450);
DOT 1 (5675 2500);
DOT 1 (5675 2550);
DOT 1 (5675 2600);
DOT 1 (5675 2650);
DOT 1 (5675 2700);
DOT 1 (5675 2750);
DOT 1 (5675 2800);
DOT 1 (5675 2850);
DOT 1 (5675 2900);
DOT 1 (5675 2950);
DOT 1 (5675 3000);
DOT 1 (5675 3050);
DOT 1 (5675 3100);
DOT 1 (5675 3150);
DOT 1 (5675 3200);
DOT 1 (5675 3250);
DOT 1 (5675 3300);
DOT 1 (5675 3350);
DOT 1 (5675 3400);
DOT 1 (5675 3450);
DOT 1 (5675 3500);
DOT 1 (5675 3550);
DOT 1 (5675 3650);
DOT 1 (5675 3700);
DOT 1 (5675 3750);
DOT 1 (5675 3800);
DOT 1 (5675 3850);
DOT 1 (5675 3900);
DOT 1 (5675 3950);
DOT 1 (5675 4000);
DOT 1 (5675 4050);
DOT 1 (5675 4100);
DOT 1 (5675 4150);
DOT 1 (5675 3600);
DOT 1 (3975 3150);
DOT 1 (3975 3100);
DOT 1 (3975 2400);
DOT 1 (3975 1050);
FORCENOTE
20210728 MODIFY FOR GT
(-3375 4925) 0;
DISPLAY LEFT (-3375 4925);
DISPLAY 2.510638 (-3375 4925);
PAINT PINK (-3375 4925);
QUIT
